FILE_TYPE = MACRO_DRAWING;
SET COLOR_WIRE YELLOW;
SET COLOR_PROP ORANGE;
SET COLOR_DOT WHITE;
SET COLOR_ARC YELLOW;
SET COLOR_BODY GREEN;
SET COLOR_NOTE PURPLE;
SET PROP_DISPLAY VALUE;
SET PAGE_NUMBER P516;
FORCEADD RESISTOR..2
(-13950 6100);
FORCEPROP 1 LAST $LOCATION R47
J 0
(-13900 5950);
DISPLAY 1.212766 (-13900 5950);
PAINT GREEN (-13900 5950);
FORCEPROP 0 LAST CDS_LOCATION R47
J 0
(-13900 6300);
DISPLAY 1.021277 (-13900 6300);
DISPLAY INVISIBLE (-13900 6300);
FORCEPROP 0 LAST $SEC 1
J 0
(-13900 6300);
DISPLAY 0.680851 (-13900 6300);
PAINT MONO (-13900 6300);
DISPLAY INVISIBLE (-13900 6300);
FORCEPROP 0 LAST CDS_SEC 1
J 0
(-13900 6300);
DISPLAY 1.021277 (-13900 6300);
DISPLAY INVISIBLE (-13900 6300);
FORCEPROP 0 LASTPIN (-13950 6200) $PN 1
R 1
J 0
(-13960 6210);
DISPLAY 0.680851 (-13960 6210);
PAINT MONO (-13960 6210);
FORCEPROP 0 LASTPIN (-13950 5950) $PN 2
R 1
J 2
(-13960 5940);
DISPLAY 0.680851 (-13960 5940);
PAINT MONO (-13960 5940);
FORCEPROP 1 LAST VALUE 10KOHM
J 0
(-13900 6200);
DISPLAY 1.212766 (-13900 6200);
PAINT GREEN (-13900 6200);
FORCEPROP 0 LAST PACKAGE 0402
J 0
(-13900 6350);
DISPLAY 1.021277 (-13900 6350);
FORCEPROP 0 LAST NO_ASSY TRUE
J 0
(-13850 6050);
DISPLAY 1.021277 (-13850 6050);
DISPLAY BOTH (-13850 6050);
FORCEPROP 1 LAST PATH I1
J 0
(-14147 6205);
DISPLAY 1.212766 (-14147 6205);
PAINT GREEN (-14147 6205);
DISPLAY INVISIBLE (-14147 6205);
FORCEPROP 1 LAST TOLERANCE 1%
J 0
(-14147 6355);
DISPLAY 1.212766 (-14147 6355);
PAINT GREEN (-14147 6355);
DISPLAY INVISIBLE (-14147 6355);
FORCEPROP 1 LAST CLS_PN G155-11002-01
J 0
(-14086 6300);
DISPLAY 1.212766 (-14086 6300);
PAINT GREEN (-14086 6300);
DISPLAY INVISIBLE (-14086 6300);
FORCEPROP 1 LAST CDS_LMAN_SYM_OUTLINE -50,50,50,-100
J 0
(-13950 6100);
DISPLAY 0.468085 (-13950 6100);
PAINT GREEN (-13950 6100);
DISPLAY INVISIBLE (-13950 6100);
FORCEPROP 2 LAST CDS_LIB passive
J 0
(-13950 6100);
DISPLAY INVISIBLE (-13950 6100);
FORCEADD CAPACITOR..2
(-12600 6600);
FORCEPROP 1 LAST $LOCATION C29
J 0
(-12500 6650);
DISPLAY 1.212766 (-12500 6650);
PAINT GREEN (-12500 6650);
FORCEPROP 0 LAST CDS_LOCATION C29
J 0
(-12500 6850);
DISPLAY INVISIBLE (-12500 6850);
FORCEPROP 0 LAST $SEC 1
J 0
(-12550 6750);
PAINT MONO (-12550 6750);
DISPLAY INVISIBLE (-12550 6750);
FORCEPROP 0 LAST CDS_SEC 1
J 0
(-12550 6750);
PAINT MONO (-12550 6750);
DISPLAY INVISIBLE (-12550 6750);
FORCEPROP 0 LASTPIN (-12600 6700) $PN 1
R 1
J 0
(-12610 6710);
DISPLAY 0.808511 (-12610 6710);
PAINT MONO (-12610 6710);
FORCEPROP 0 LASTPIN (-12600 6450) $PN 2
R 1
J 2
(-12610 6440);
DISPLAY 0.808511 (-12610 6440);
PAINT MONO (-12610 6440);
FORCEPROP 0 LAST PACKAGE 0402
J 0
(-12500 6800);
DISPLAY 1.021277 (-12500 6800);
FORCEPROP 1 LAST VALUE 0.1UF
J 0
(-12500 6450);
DISPLAY 1.212766 (-12500 6450);
PAINT GREEN (-12500 6450);
FORCEPROP 0 LAST VOLTAGE 10V
J 0
(-12500 6900);
DISPLAY 1.021277 (-12500 6900);
FORCEPROP 1 LAST PATH I10
J 0
(-12700 6650);
DISPLAY 1.212766 (-12700 6650);
PAINT GREEN (-12700 6650);
DISPLAY INVISIBLE (-12700 6650);
FORCEPROP 1 LAST CDS_LMAN_SYM_OUTLINE -50,0,50,-50
J 0
(-12600 6600);
DISPLAY 0.468085 (-12600 6600);
PAINT GREEN (-12600 6600);
DISPLAY INVISIBLE (-12600 6600);
FORCEPROP 2 LAST CDS_LIB passive
J 0
(-12600 6600);
DISPLAY INVISIBLE (-12600 6600);
FORCEPROP 1 LAST CLS_PN G105-0B104-CK
J 0
(-12700 6650);
DISPLAY 1.212766 (-12700 6650);
PAINT GREEN (-12700 6650);
DISPLAY INVISIBLE (-12700 6650);
FORCEPROP 1 LAST TOLERANCE 10%
J 0
(-12750 6700);
DISPLAY 1.212766 (-12750 6700);
PAINT GREEN (-12750 6700);
DISPLAY INVISIBLE (-12750 6700);
FORCEADD CAPACITOR..2
(-11850 6100);
FORCEPROP 1 LAST $LOCATION C31
J 0
(-11750 6000);
DISPLAY 1.212766 (-11750 6000);
PAINT GREEN (-11750 6000);
FORCEPROP 0 LAST CDS_LOCATION C31
J 0
(-11800 5950);
DISPLAY 1.212766 (-11800 5950);
PAINT GREEN (-11800 5950);
DISPLAY INVISIBLE (-11800 5950);
FORCEPROP 0 LAST $SEC 1
J 0
(-11800 6250);
DISPLAY 0.680851 (-11800 6250);
PAINT MONO (-11800 6250);
DISPLAY INVISIBLE (-11800 6250);
FORCEPROP 0 LAST CDS_SEC 1
J 0
(-11800 6250);
DISPLAY 1.021277 (-11800 6250);
DISPLAY INVISIBLE (-11800 6250);
FORCEPROP 0 LASTPIN (-11850 6200) $PN 1
R 1
J 0
(-11860 6210);
DISPLAY 0.680851 (-11860 6210);
PAINT MONO (-11860 6210);
FORCEPROP 0 LASTPIN (-11850 5950) $PN 2
R 1
J 2
(-11860 5940);
DISPLAY 0.680851 (-11860 5940);
PAINT MONO (-11860 5940);
FORCEPROP 1 LAST VALUE 0.022UF
J 0
(-11800 6150);
DISPLAY 1.212766 (-11800 6150);
PAINT GREEN (-11800 6150);
FORCEPROP 0 LAST PACKAGE 0402
J 0
(-11750 6250);
DISPLAY 1.021277 (-11750 6250);
FORCEPROP 0 LAST VOLTAGE 25V
J 0
(-11750 6350);
DISPLAY 1.021277 (-11750 6350);
FORCEPROP 1 LAST PATH I11
J 0
(-11950 6150);
DISPLAY 1.212766 (-11950 6150);
PAINT GREEN (-11950 6150);
DISPLAY INVISIBLE (-11950 6150);
FORCEPROP 1 LAST CLS_PN G105-0B223-EK
J 0
(-11950 6150);
DISPLAY 1.212766 (-11950 6150);
PAINT GREEN (-11950 6150);
DISPLAY INVISIBLE (-11950 6150);
FORCEPROP 1 LAST CDS_LMAN_SYM_OUTLINE -50,0,50,-50
J 0
(-11850 6100);
DISPLAY 0.468085 (-11850 6100);
PAINT GREEN (-11850 6100);
DISPLAY INVISIBLE (-11850 6100);
FORCEPROP 2 LAST CDS_LIB passive
J 0
(-11850 6100);
DISPLAY INVISIBLE (-11850 6100);
FORCEPROP 1 LAST TOLERANCE 10%
J 0
(-12000 6200);
DISPLAY 1.212766 (-12000 6200);
PAINT GREEN (-12000 6200);
DISPLAY INVISIBLE (-12000 6200);
FORCEADD RESISTOR..2
(-11300 5900);
FORCEPROP 1 LAST $LOCATION R29
J 0
(-11200 5700);
DISPLAY 1.212766 (-11200 5700);
PAINT GREEN (-11200 5700);
FORCEPROP 0 LAST CDS_LOCATION R29
J 0
(-11250 5750);
DISPLAY 1.212766 (-11250 5750);
PAINT GREEN (-11250 5750);
DISPLAY INVISIBLE (-11250 5750);
FORCEPROP 0 LAST $SEC 1
J 0
(-11250 6050);
DISPLAY 0.680851 (-11250 6050);
PAINT MONO (-11250 6050);
DISPLAY INVISIBLE (-11250 6050);
FORCEPROP 0 LAST CDS_SEC 1
J 0
(-11250 6050);
DISPLAY 1.021277 (-11250 6050);
DISPLAY INVISIBLE (-11250 6050);
FORCEPROP 0 LASTPIN (-11300 6000) $PN 1
R 1
J 0
(-11310 6010);
DISPLAY 0.680851 (-11310 6010);
PAINT MONO (-11310 6010);
FORCEPROP 0 LASTPIN (-11300 5750) $PN 2
R 1
J 2
(-11310 5740);
DISPLAY 0.680851 (-11310 5740);
PAINT MONO (-11310 5740);
FORCEPROP 1 LAST VALUE 100KOHM
J 0
(-11250 5850);
DISPLAY 1.212766 (-11250 5850);
PAINT GREEN (-11250 5850);
FORCEPROP 0 LAST PACKAGE 0402
J 0
(-11200 5950);
DISPLAY 1.021277 (-11200 5950);
FORCEPROP 1 LAST PATH I12
J 0
(-11497 6005);
DISPLAY 1.212766 (-11497 6005);
PAINT GREEN (-11497 6005);
DISPLAY INVISIBLE (-11497 6005);
FORCEPROP 1 LAST TOLERANCE 1%
J 0
(-11497 6155);
DISPLAY 1.212766 (-11497 6155);
PAINT GREEN (-11497 6155);
DISPLAY INVISIBLE (-11497 6155);
FORCEPROP 2 LAST CDS_LIB passive
J 0
(-11300 5900);
DISPLAY INVISIBLE (-11300 5900);
FORCEPROP 1 LAST CDS_LMAN_SYM_OUTLINE -50,50,50,-100
J 0
(-11300 5900);
DISPLAY 0.468085 (-11300 5900);
PAINT GREEN (-11300 5900);
DISPLAY INVISIBLE (-11300 5900);
FORCEPROP 1 LAST CLS_PN G155-11003-01
J 0
(-11436 6100);
DISPLAY 1.212766 (-11436 6100);
PAINT GREEN (-11436 6100);
DISPLAY INVISIBLE (-11436 6100);
FORCEADD CAPACITOR..2
(-10700 5750);
FORCEPROP 1 LAST $LOCATION C42
J 0
(-10650 5800);
DISPLAY 1.212766 (-10650 5800);
PAINT GREEN (-10650 5800);
FORCEPROP 0 LAST CDS_LOCATION C42
J 0
(-10650 5600);
DISPLAY 1.212766 (-10650 5600);
PAINT GREEN (-10650 5600);
DISPLAY INVISIBLE (-10650 5600);
FORCEPROP 0 LAST $SEC 1
J 0
(-10650 5900);
DISPLAY 0.680851 (-10650 5900);
PAINT MONO (-10650 5900);
DISPLAY INVISIBLE (-10650 5900);
FORCEPROP 0 LAST CDS_SEC 1
J 0
(-10650 5900);
DISPLAY 1.021277 (-10650 5900);
DISPLAY INVISIBLE (-10650 5900);
FORCEPROP 0 LASTPIN (-10700 5850) $PN 1
R 1
J 0
(-10710 5860);
DISPLAY 0.680851 (-10710 5860);
PAINT MONO (-10710 5860);
FORCEPROP 0 LASTPIN (-10700 5600) $PN 2
R 1
J 2
(-10710 5590);
DISPLAY 0.680851 (-10710 5590);
PAINT MONO (-10710 5590);
FORCEPROP 1 LAST VALUE 2200PF
J 0
(-10650 5600);
DISPLAY 1.212766 (-10650 5600);
PAINT GREEN (-10650 5600);
FORCEPROP 0 LAST VOLTAGE 50V
J 0
(-10450 5800);
DISPLAY 1.021277 (-10450 5800);
FORCEPROP 0 LAST PACKAGE 0402
J 0
(-10500 5700);
DISPLAY 1.021277 (-10500 5700);
FORCEPROP 1 LAST CLS_PN G105-0B222-FK
J 0
(-10800 5800);
DISPLAY 1.212766 (-10800 5800);
PAINT GREEN (-10800 5800);
DISPLAY INVISIBLE (-10800 5800);
FORCEPROP 2 LASTPIN (-10700 5850) SIG_NAME UN$516$CAPACITOR$I13$1
J 0
(-10690 5860);
DISPLAY 0.659574 (-10690 5860);
PAINT MONO (-10690 5860);
DISPLAY INVISIBLE (-10690 5860);
FORCEPROP 2 LAST CDS_LIB passive
J 0
(-10700 5750);
DISPLAY INVISIBLE (-10700 5750);
FORCEPROP 1 LAST CDS_LMAN_SYM_OUTLINE -50,0,50,-50
J 0
(-10700 5750);
DISPLAY 0.468085 (-10700 5750);
PAINT GREEN (-10700 5750);
DISPLAY INVISIBLE (-10700 5750);
FORCEPROP 1 LAST TOLERANCE 10%
J 0
(-10850 5850);
DISPLAY 1.212766 (-10850 5850);
PAINT GREEN (-10850 5850);
DISPLAY INVISIBLE (-10850 5850);
FORCEPROP 1 LAST PATH I13
J 0
(-10800 5800);
DISPLAY 1.212766 (-10800 5800);
PAINT GREEN (-10800 5800);
DISPLAY INVISIBLE (-10800 5800);
FORCEADD RESISTOR..2
(-10700 6050);
FORCEPROP 1 LAST $LOCATION R30
J 0
(-10650 6050);
DISPLAY 1.212766 (-10650 6050);
PAINT GREEN (-10650 6050);
FORCEPROP 0 LAST CDS_LOCATION R30
J 0
(-10650 5900);
DISPLAY 1.212766 (-10650 5900);
PAINT GREEN (-10650 5900);
DISPLAY INVISIBLE (-10650 5900);
FORCEPROP 0 LAST $SEC 1
J 0
(-10650 6200);
DISPLAY 0.680851 (-10650 6200);
PAINT MONO (-10650 6200);
DISPLAY INVISIBLE (-10650 6200);
FORCEPROP 0 LAST CDS_SEC 1
J 0
(-10650 6200);
DISPLAY 1.021277 (-10650 6200);
DISPLAY INVISIBLE (-10650 6200);
FORCEPROP 0 LASTPIN (-10700 6150) $PN 1
R 1
J 0
(-10710 6160);
DISPLAY 0.680851 (-10710 6160);
PAINT MONO (-10710 6160);
FORCEPROP 0 LASTPIN (-10700 5900) $PN 2
R 1
J 2
(-10710 5890);
DISPLAY 0.680851 (-10710 5890);
PAINT MONO (-10710 5890);
FORCEPROP 1 LAST VALUE 2.2KOHM
J 0
(-10650 5950);
DISPLAY 1.212766 (-10650 5950);
PAINT GREEN (-10650 5950);
FORCEPROP 0 LAST PACKAGE 0402
J 0
(-10450 6050);
DISPLAY 1.021277 (-10450 6050);
FORCEPROP 1 LAST CLS_PN G155-12201-01
J 0
(-10836 6250);
DISPLAY 1.212766 (-10836 6250);
PAINT GREEN (-10836 6250);
DISPLAY INVISIBLE (-10836 6250);
FORCEPROP 1 LAST CDS_LMAN_SYM_OUTLINE -50,50,50,-100
J 0
(-10700 6050);
DISPLAY 0.468085 (-10700 6050);
PAINT GREEN (-10700 6050);
DISPLAY INVISIBLE (-10700 6050);
FORCEPROP 2 LAST CDS_LIB passive
J 0
(-10700 6050);
DISPLAY INVISIBLE (-10700 6050);
FORCEPROP 1 LAST TOLERANCE 1%
J 0
(-10897 6305);
DISPLAY 1.212766 (-10897 6305);
PAINT GREEN (-10897 6305);
DISPLAY INVISIBLE (-10897 6305);
FORCEPROP 1 LAST PATH I14
J 0
(-10897 6155);
DISPLAY 1.212766 (-10897 6155);
PAINT GREEN (-10897 6155);
DISPLAY INVISIBLE (-10897 6155);
FORCEADD CAPACITOR..2
(-10050 5850);
FORCEPROP 1 LAST $LOCATION C43
J 0
(-10000 5700);
DISPLAY 1.212766 (-10000 5700);
PAINT GREEN (-10000 5700);
FORCEPROP 0 LAST CDS_LOCATION C43
J 0
(-10000 5700);
DISPLAY 1.212766 (-10000 5700);
PAINT GREEN (-10000 5700);
DISPLAY INVISIBLE (-10000 5700);
FORCEPROP 0 LAST $SEC 1
J 0
(-10000 6000);
DISPLAY 0.680851 (-10000 6000);
PAINT MONO (-10000 6000);
DISPLAY INVISIBLE (-10000 6000);
FORCEPROP 0 LAST CDS_SEC 1
J 0
(-10000 6000);
DISPLAY 1.021277 (-10000 6000);
DISPLAY INVISIBLE (-10000 6000);
FORCEPROP 0 LASTPIN (-10050 5950) $PN 1
R 1
J 0
(-10060 5960);
DISPLAY 0.680851 (-10060 5960);
PAINT MONO (-10060 5960);
FORCEPROP 0 LASTPIN (-10050 5700) $PN 2
R 1
J 2
(-10060 5690);
DISPLAY 0.680851 (-10060 5690);
PAINT MONO (-10060 5690);
FORCEPROP 1 LAST VALUE 18PF
J 0
(-10000 5900);
DISPLAY 1.212766 (-10000 5900);
PAINT GREEN (-10000 5900);
FORCEPROP 0 LAST PACKAGE 0201
J 0
(-10000 6050);
DISPLAY 1.021277 (-10000 6050);
FORCEPROP 0 LAST VOLTAGE 50V
J 0
(-10000 6150);
DISPLAY 1.021277 (-10000 6150);
FORCEPROP 1 LAST PATH I15
J 0
(-10150 5900);
DISPLAY 1.212766 (-10150 5900);
PAINT GREEN (-10150 5900);
DISPLAY INVISIBLE (-10150 5900);
FORCEPROP 1 LAST TOLERANCE 5%
J 0
(-10200 5950);
DISPLAY 1.212766 (-10200 5950);
PAINT GREEN (-10200 5950);
DISPLAY INVISIBLE (-10200 5950);
FORCEPROP 1 LAST CLS_PN G104-0A180-FJ
J 0
(-10150 5900);
DISPLAY 1.212766 (-10150 5900);
PAINT GREEN (-10150 5900);
DISPLAY INVISIBLE (-10150 5900);
FORCEPROP 1 LAST CDS_LMAN_SYM_OUTLINE -50,0,50,-50
J 0
(-10050 5850);
DISPLAY 0.468085 (-10050 5850);
PAINT GREEN (-10050 5850);
DISPLAY INVISIBLE (-10050 5850);
FORCEPROP 2 LAST CDS_LIB passive
J 0
(-10050 5850);
DISPLAY INVISIBLE (-10050 5850);
FORCEADD RESISTOR..2
(-12700 7900);
FORCEPROP 1 LAST $LOCATION R49
J 0
(-12650 7750);
DISPLAY 1.212766 (-12650 7750);
PAINT GREEN (-12650 7750);
FORCEPROP 0 LAST CDS_LOCATION R49
J 0
(-13100 8000);
DISPLAY 1.021277 (-13100 8000);
DISPLAY INVISIBLE (-13100 8000);
FORCEPROP 0 LAST $SEC 1
J 0
(-13100 8000);
DISPLAY 0.680851 (-13100 8000);
PAINT MONO (-13100 8000);
DISPLAY INVISIBLE (-13100 8000);
FORCEPROP 0 LAST CDS_SEC 1
J 0
(-13100 8000);
DISPLAY 1.021277 (-13100 8000);
DISPLAY INVISIBLE (-13100 8000);
FORCEPROP 0 LASTPIN (-12700 8000) $PN 1
R 1
J 0
(-12710 8010);
DISPLAY 0.680851 (-12710 8010);
PAINT MONO (-12710 8010);
FORCEPROP 0 LASTPIN (-12700 7750) $PN 2
R 1
J 2
(-12710 7740);
DISPLAY 0.680851 (-12710 7740);
PAINT MONO (-12710 7740);
FORCEPROP 1 LAST VALUE 10KOHM
J 0
(-13100 7900);
DISPLAY 1.212766 (-13100 7900);
PAINT GREEN (-13100 7900);
FORCEPROP 0 LAST PACKAGE 0402
J 0
(-13050 8000);
DISPLAY 1.021277 (-13050 8000);
FORCEPROP 0 LAST NO_ASSY TRUE
J 0
(-13350 7800);
DISPLAY 1.021277 (-13350 7800);
DISPLAY BOTH (-13350 7800);
FORCEPROP 1 LAST PATH I16
J 0
(-12897 8005);
DISPLAY 1.212766 (-12897 8005);
PAINT GREEN (-12897 8005);
DISPLAY INVISIBLE (-12897 8005);
FORCEPROP 1 LAST TOLERANCE 1%
J 0
(-12897 8155);
DISPLAY 1.212766 (-12897 8155);
PAINT GREEN (-12897 8155);
DISPLAY INVISIBLE (-12897 8155);
FORCEPROP 1 LAST CLS_PN G155-11002-01
J 0
(-12836 8100);
DISPLAY 1.212766 (-12836 8100);
PAINT GREEN (-12836 8100);
DISPLAY INVISIBLE (-12836 8100);
FORCEPROP 2 LAST CDS_LIB passive
J 0
(-12700 7900);
DISPLAY INVISIBLE (-12700 7900);
FORCEPROP 1 LAST CDS_LMAN_SYM_OUTLINE -50,50,50,-100
J 0
(-12700 7900);
DISPLAY 0.468085 (-12700 7900);
PAINT GREEN (-12700 7900);
DISPLAY INVISIBLE (-12700 7900);
FORCEADD FERRITEBEAD..1
(-13200 8300);
FORCEPROP 1 LAST $LOCATION L7
J 2
(-13260 8359);
DISPLAY 1.212766 (-13260 8359);
PAINT GREEN (-13260 8359);
FORCEPROP 0 LAST CDS_LOCATION L7
J 0
(-13250 8450);
DISPLAY 1.021277 (-13250 8450);
DISPLAY INVISIBLE (-13250 8450);
FORCEPROP 0 LAST $SEC 1
J 0
(-13250 8450);
DISPLAY 0.680851 (-13250 8450);
PAINT MONO (-13250 8450);
DISPLAY INVISIBLE (-13250 8450);
FORCEPROP 0 LAST CDS_SEC 1
J 0
(-13250 8450);
DISPLAY 1.021277 (-13250 8450);
DISPLAY INVISIBLE (-13250 8450);
FORCEPROP 0 LASTPIN (-13300 8250) $PN 1
J 2
(-13310 8260);
DISPLAY 0.680851 (-13310 8260);
PAINT MONO (-13310 8260);
FORCEPROP 0 LASTPIN (-12900 8250) $PN 2
J 0
(-12890 8260);
DISPLAY 0.680851 (-12890 8260);
PAINT MONO (-12890 8260);
FORCEPROP 0 LAST PACKAGE 0603
J 0
(-13200 8350);
DISPLAY 1.021277 (-13200 8350);
FORCEPROP 1 LAST VALUE 26OHM
J 0
(-12850 8250);
DISPLAY 1.212766 (-12850 8250);
PAINT GREEN (-12850 8250);
FORCEPROP 1 LAST TOLERANCE 25%
J 0
(-13300 8350);
DISPLAY 1.212766 (-13300 8350);
PAINT GREEN (-13300 8350);
DISPLAY INVISIBLE (-13300 8350);
FORCEPROP 1 LAST PATH I17
J 2
(-13250 8350);
DISPLAY 1.212766 (-13250 8350);
PAINT GREEN (-13250 8350);
DISPLAY INVISIBLE (-13250 8350);
FORCEPROP 1 LAST CLS_PN G191-10101-01
J 2
(-13250 8350);
DISPLAY 1.212766 (-13250 8350);
PAINT GREEN (-13250 8350);
DISPLAY INVISIBLE (-13250 8350);
FORCEPROP 1 LAST CDS_LMAN_SYM_OUTLINE 0,0,200,-100
J 0
(-13200 8300);
DISPLAY 0.468085 (-13200 8300);
PAINT GREEN (-13200 8300);
DISPLAY INVISIBLE (-13200 8300);
FORCEPROP 2 LAST CDS_LIB passive
J 0
(-13200 8300);
DISPLAY INVISIBLE (-13200 8300);
FORCEADD CAPACITOR..2
(-12250 7950);
FORCEPROP 1 LAST $LOCATION C30
J 0
(-12150 7900);
DISPLAY 1.212766 (-12150 7900);
PAINT GREEN (-12150 7900);
FORCEPROP 0 LAST CDS_LOCATION C30
J 0
(-12200 8200);
DISPLAY INVISIBLE (-12200 8200);
FORCEPROP 0 LAST $SEC 1
J 0
(-12200 8100);
DISPLAY INVISIBLE (-12200 8100);
FORCEPROP 0 LAST CDS_SEC 1
J 0
(-12200 8100);
DISPLAY INVISIBLE (-12200 8100);
FORCEPROP 0 LASTPIN (-12250 8050) $PN 1
R 1
J 0
(-12260 8060);
DISPLAY 0.808511 (-12260 8060);
FORCEPROP 0 LASTPIN (-12250 7800) $PN 2
R 1
J 2
(-12260 7790);
DISPLAY 0.808511 (-12260 7790);
FORCEPROP 0 LAST PACKAGE 0805
J 0
(-12150 8000);
DISPLAY 1.021277 (-12150 8000);
FORCEPROP 0 LAST VOLTAGE 25V
J 0
(-12150 8100);
DISPLAY 1.021277 (-12150 8100);
FORCEPROP 1 LAST VALUE 10UF
J 0
(-12150 7800);
DISPLAY 1.212766 (-12150 7800);
PAINT GREEN (-12150 7800);
FORCEPROP 1 LAST PATH I18
J 0
(-12350 8000);
DISPLAY 1.212766 (-12350 8000);
PAINT GREEN (-12350 8000);
DISPLAY INVISIBLE (-12350 8000);
FORCEPROP 1 LAST CLS_PN G107-0F106-EM
J 0
(-12350 8000);
DISPLAY 1.212766 (-12350 8000);
PAINT GREEN (-12350 8000);
DISPLAY INVISIBLE (-12350 8000);
FORCEPROP 1 LAST CDS_LMAN_SYM_OUTLINE -50,0,50,-50
J 0
(-12250 7950);
DISPLAY 0.468085 (-12250 7950);
PAINT GREEN (-12250 7950);
DISPLAY INVISIBLE (-12250 7950);
FORCEPROP 2 LAST CDS_LIB passive
J 0
(-12250 7950);
DISPLAY INVISIBLE (-12250 7950);
FORCEPROP 1 LAST TOLERANCE 20%
J 0
(-12400 8050);
DISPLAY 1.212766 (-12400 8050);
PAINT GREEN (-12400 8050);
DISPLAY INVISIBLE (-12400 8050);
FORCEADD CAPACITOR..2
(-11800 7950);
FORCEPROP 1 LAST $LOCATION C32
J 0
(-11700 7900);
DISPLAY 1.212766 (-11700 7900);
PAINT GREEN (-11700 7900);
FORCEPROP 0 LAST CDS_LOCATION C32
J 0
(-11750 8200);
DISPLAY INVISIBLE (-11750 8200);
FORCEPROP 0 LAST $SEC 1
J 0
(-11750 8100);
DISPLAY INVISIBLE (-11750 8100);
FORCEPROP 0 LAST CDS_SEC 1
J 0
(-11750 8100);
DISPLAY INVISIBLE (-11750 8100);
FORCEPROP 0 LASTPIN (-11800 8050) $PN 1
R 1
J 0
(-11810 8060);
DISPLAY 0.808511 (-11810 8060);
FORCEPROP 0 LASTPIN (-11800 7800) $PN 2
R 1
J 2
(-11810 7790);
DISPLAY 0.808511 (-11810 7790);
FORCEPROP 0 LAST PACKAGE 0805
J 0
(-11700 8000);
DISPLAY 1.021277 (-11700 8000);
FORCEPROP 0 LAST VOLTAGE 25V
J 0
(-11700 8100);
DISPLAY 1.021277 (-11700 8100);
FORCEPROP 1 LAST VALUE 10UF
J 0
(-11700 7800);
DISPLAY 1.212766 (-11700 7800);
PAINT GREEN (-11700 7800);
FORCEPROP 1 LAST PATH I19
J 0
(-11900 8000);
DISPLAY 1.212766 (-11900 8000);
PAINT GREEN (-11900 8000);
DISPLAY INVISIBLE (-11900 8000);
FORCEPROP 2 LAST CDS_LIB passive
J 0
(-11800 7950);
DISPLAY INVISIBLE (-11800 7950);
FORCEPROP 1 LAST CDS_LMAN_SYM_OUTLINE -50,0,50,-50
J 0
(-11800 7950);
DISPLAY 0.468085 (-11800 7950);
PAINT GREEN (-11800 7950);
DISPLAY INVISIBLE (-11800 7950);
FORCEPROP 1 LAST CLS_PN G107-0F106-EM
J 0
(-11900 8000);
DISPLAY 1.212766 (-11900 8000);
PAINT GREEN (-11900 8000);
DISPLAY INVISIBLE (-11900 8000);
FORCEPROP 1 LAST TOLERANCE 20%
J 0
(-11950 8050);
DISPLAY 1.212766 (-11950 8050);
PAINT GREEN (-11950 8050);
DISPLAY INVISIBLE (-11950 8050);
FORCEADD VCC..1
(-14000 6500);
FORCEPROP 3 LASTPIN (-13950 6450) SIG_NAME XP3R3V\g
J 0
(-13940 6460);
DISPLAY 0.659574 (-13940 6460);
PAINT MONO (-13940 6460);
DISPLAY INVISIBLE (-13940 6460);
FORCEPROP 1 LAST HDL_POWER XP3R3V
J 1
(-13945 6555);
DISPLAY 1.021277 (-13945 6555);
PAINT GREEN (-13945 6555);
FORCEPROP 0 LAST VOLTAGE 3.3
J 0
(-14200 6600);
DISPLAY 1.021277 (-14200 6600);
DISPLAY BOTH (-14200 6600);
FORCEPROP 1 LAST PATH I2
J 0
(-13965 6590);
DISPLAY 0.808511 (-13965 6590);
PAINT GREEN (-13965 6590);
DISPLAY INVISIBLE (-13965 6590);
FORCEPROP 1 LAST BODY_TYPE PLUMBING
J 0
(-14045 6457);
DISPLAY 0.340426 (-14045 6457);
PAINT GREEN (-14045 6457);
DISPLAY INVISIBLE (-14045 6457);
FORCEPROP 1 LAST CDS_LMAN_SYM_OUTLINE -250,250,250,-250
J 0
(-14000 6500);
DISPLAY 0.468085 (-14000 6500);
PAINT GREEN (-14000 6500);
DISPLAY INVISIBLE (-14000 6500);
FORCEPROP 2 LAST CDS_LIB cls
J 0
(-14000 6500);
DISPLAY INVISIBLE (-14000 6500);
FORCEADD CAPACITOR..2
(-11350 7950);
FORCEPROP 1 LAST $LOCATION C33
J 0
(-11250 7850);
DISPLAY 1.212766 (-11250 7850);
PAINT GREEN (-11250 7850);
FORCEPROP 0 LAST CDS_LOCATION C33
J 0
(-11250 8100);
DISPLAY 1.021277 (-11250 8100);
DISPLAY INVISIBLE (-11250 8100);
FORCEPROP 0 LAST $SEC 1
J 0
(-11250 8100);
DISPLAY 0.680851 (-11250 8100);
PAINT MONO (-11250 8100);
DISPLAY INVISIBLE (-11250 8100);
FORCEPROP 0 LAST CDS_SEC 1
J 0
(-11250 8100);
DISPLAY 1.021277 (-11250 8100);
DISPLAY INVISIBLE (-11250 8100);
FORCEPROP 0 LASTPIN (-11350 8050) $PN 1
R 1
J 0
(-11360 8060);
DISPLAY 0.680851 (-11360 8060);
PAINT MONO (-11360 8060);
FORCEPROP 0 LASTPIN (-11350 7800) $PN 2
R 1
J 2
(-11360 7790);
DISPLAY 0.680851 (-11360 7790);
PAINT MONO (-11360 7790);
FORCEPROP 0 LAST PACKAGE 0402
J 0
(-11250 8000);
DISPLAY 1.021277 (-11250 8000);
FORCEPROP 0 LAST VOLTAGE 25V
J 0
(-11250 8100);
DISPLAY 1.021277 (-11250 8100);
FORCEPROP 1 LAST VALUE 0.1UF
J 0
(-11250 7750);
DISPLAY 1.212766 (-11250 7750);
PAINT GREEN (-11250 7750);
FORCEPROP 1 LAST PATH I20
J 0
(-11450 8000);
DISPLAY 1.212766 (-11450 8000);
PAINT GREEN (-11450 8000);
DISPLAY INVISIBLE (-11450 8000);
FORCEPROP 1 LAST CLS_PN G105-0B104-EK
J 0
(-11450 8000);
DISPLAY 1.212766 (-11450 8000);
PAINT GREEN (-11450 8000);
DISPLAY INVISIBLE (-11450 8000);
FORCEPROP 1 LAST CDS_LMAN_SYM_OUTLINE -50,0,50,-50
J 0
(-11350 7950);
DISPLAY 0.468085 (-11350 7950);
PAINT GREEN (-11350 7950);
DISPLAY INVISIBLE (-11350 7950);
FORCEPROP 2 LAST CDS_LIB passive
J 0
(-11350 7950);
DISPLAY INVISIBLE (-11350 7950);
FORCEPROP 1 LAST TOLERANCE 10%
J 0
(-11500 8050);
DISPLAY 1.212766 (-11500 8050);
PAINT GREEN (-11500 8050);
DISPLAY INVISIBLE (-11500 8050);
FORCEADD GND_SG..1
(-10850 7400);
FORCEPROP 3 LASTPIN (-10800 7450) SIG_NAME SG\g
J 0
(-10790 7460);
DISPLAY 0.659574 (-10790 7460);
PAINT MONO (-10790 7460);
DISPLAY INVISIBLE (-10790 7460);
FORCEPROP 1 LAST HDL_POWER SG
J 1
(-10795 7305);
DISPLAY 0.808511 (-10795 7305);
PAINT GREEN (-10795 7305);
FORCEPROP 1 LAST PATH I21
J 0
(-10815 7400);
DISPLAY 0.808511 (-10815 7400);
PAINT GREEN (-10815 7400);
DISPLAY INVISIBLE (-10815 7400);
FORCEPROP 1 LAST BODY_TYPE PLUMBING
J 0
(-10835 7385);
DISPLAY 0.808511 (-10835 7385);
PAINT GREEN (-10835 7385);
DISPLAY INVISIBLE (-10835 7385);
FORCEPROP 2 LAST CDS_LIB cls
J 0
(-10850 7400);
DISPLAY INVISIBLE (-10850 7400);
FORCEPROP 1 LAST CDS_LMAN_SYM_OUTLINE 0,0,100,-50
J 0
(-10850 7400);
DISPLAY 0.468085 (-10850 7400);
PAINT GREEN (-10850 7400);
DISPLAY INVISIBLE (-10850 7400);
FORCEADD CAPACITOR..2
(-10800 7950);
FORCEPROP 1 LAST $LOCATION C41
J 0
(-10700 7850);
DISPLAY 1.212766 (-10700 7850);
PAINT GREEN (-10700 7850);
FORCEPROP 0 LAST CDS_LOCATION C41
J 0
(-10700 8000);
DISPLAY 1.021277 (-10700 8000);
DISPLAY INVISIBLE (-10700 8000);
FORCEPROP 0 LAST $SEC 1
J 0
(-10700 8000);
DISPLAY 0.680851 (-10700 8000);
PAINT MONO (-10700 8000);
DISPLAY INVISIBLE (-10700 8000);
FORCEPROP 0 LAST CDS_SEC 1
J 0
(-10700 8000);
DISPLAY 1.021277 (-10700 8000);
DISPLAY INVISIBLE (-10700 8000);
FORCEPROP 0 LASTPIN (-10800 8050) $PN 1
R 1
J 0
(-10810 8060);
DISPLAY 0.680851 (-10810 8060);
PAINT MONO (-10810 8060);
FORCEPROP 0 LASTPIN (-10800 7800) $PN 2
R 1
J 2
(-10810 7790);
DISPLAY 0.680851 (-10810 7790);
PAINT MONO (-10810 7790);
FORCEPROP 0 LAST VOLTAGE 25V
J 0
(-10700 8100);
DISPLAY 1.021277 (-10700 8100);
FORCEPROP 1 LAST VALUE 0.1UF
J 0
(-10700 7750);
DISPLAY 1.212766 (-10700 7750);
PAINT GREEN (-10700 7750);
FORCEPROP 0 LAST PACKAGE 0402
J 0
(-10700 8000);
DISPLAY 1.021277 (-10700 8000);
FORCEPROP 1 LAST PATH I22
J 0
(-10900 8000);
DISPLAY 1.212766 (-10900 8000);
PAINT GREEN (-10900 8000);
DISPLAY INVISIBLE (-10900 8000);
FORCEPROP 2 LAST CDS_LIB passive
J 0
(-10800 7950);
DISPLAY INVISIBLE (-10800 7950);
FORCEPROP 1 LAST CDS_LMAN_SYM_OUTLINE -50,0,50,-50
J 0
(-10800 7950);
DISPLAY 0.468085 (-10800 7950);
PAINT GREEN (-10800 7950);
DISPLAY INVISIBLE (-10800 7950);
FORCEPROP 1 LAST CLS_PN G105-0B104-EK
J 0
(-10900 8000);
DISPLAY 1.212766 (-10900 8000);
PAINT GREEN (-10900 8000);
DISPLAY INVISIBLE (-10900 8000);
FORCEPROP 1 LAST TOLERANCE 10%
J 0
(-10950 8050);
DISPLAY 1.212766 (-10950 8050);
PAINT GREEN (-10950 8050);
DISPLAY INVISIBLE (-10950 8050);
FORCEADD GND_SG..1
(-8050 4700);
FORCEPROP 3 LASTPIN (-8000 4750) SIG_NAME SG\g
J 0
(-7990 4760);
DISPLAY 0.659574 (-7990 4760);
PAINT MONO (-7990 4760);
DISPLAY INVISIBLE (-7990 4760);
FORCEPROP 1 LAST HDL_POWER SG
J 1
(-7995 4605);
DISPLAY 0.808511 (-7995 4605);
PAINT GREEN (-7995 4605);
FORCEPROP 1 LAST PATH I23
J 0
(-8015 4700);
DISPLAY 0.808511 (-8015 4700);
PAINT GREEN (-8015 4700);
DISPLAY INVISIBLE (-8015 4700);
FORCEPROP 1 LAST BODY_TYPE PLUMBING
J 0
(-8035 4685);
DISPLAY 0.808511 (-8035 4685);
PAINT GREEN (-8035 4685);
DISPLAY INVISIBLE (-8035 4685);
FORCEPROP 2 LAST CDS_LIB cls
J 0
(-8050 4700);
DISPLAY INVISIBLE (-8050 4700);
FORCEPROP 1 LAST CDS_LMAN_SYM_OUTLINE 0,0,100,-50
J 0
(-8050 4700);
DISPLAY 0.468085 (-8050 4700);
PAINT GREEN (-8050 4700);
DISPLAY INVISIBLE (-8050 4700);
FORCEADD SOLDER_PREFORM..1
(-7500 5150);
FORCEPROP 1 LAST $LOCATION SP1
J 0
(-7450 5250);
DISPLAY 1.212766 (-7450 5250);
PAINT GREEN (-7450 5250);
FORCEPROP 0 LAST CDS_LOCATION SP1
J 0
(-7450 5550);
DISPLAY 1.021277 (-7450 5550);
DISPLAY INVISIBLE (-7450 5550);
FORCEPROP 0 LAST $SEC 1
J 0
(-7450 5450);
DISPLAY 0.680851 (-7450 5450);
PAINT MONO (-7450 5450);
DISPLAY INVISIBLE (-7450 5450);
FORCEPROP 0 LAST CDS_SEC 1
J 0
(-7450 5550);
DISPLAY 1.021277 (-7450 5550);
DISPLAY INVISIBLE (-7450 5550);
FORCEPROP 0 LASTPIN (-7600 5050) $PN 1
J 2
(-7610 5060);
DISPLAY 0.680851 (-7610 5060);
PAINT MONO (-7610 5060);
FORCEPROP 0 LASTPIN (-7150 5050) $PN 2
J 0
(-7140 5060);
DISPLAY 0.680851 (-7140 5060);
PAINT MONO (-7140 5060);
FORCEPROP 1 LAST CLS_PN G380-10015-01
J 0
(-7450 5350);
DISPLAY 1.212766 (-7450 5350);
PAINT GREEN (-7450 5350);
FORCEPROP 1 LAST PATH I24
J 0
(-7450 5200);
DISPLAY 1.212766 (-7450 5200);
PAINT GREEN (-7450 5200);
DISPLAY INVISIBLE (-7450 5200);
FORCEPROP 1 LAST CDS_LMAN_SYM_OUTLINE 0,0,250,-200
J 0
(-7500 5150);
DISPLAY 0.468085 (-7500 5150);
PAINT GREEN (-7500 5150);
DISPLAY INVISIBLE (-7500 5150);
FORCEPROP 2 LAST CDS_LIB mech
J 0
(-7500 5150);
DISPLAY INVISIBLE (-7500 5150);
FORCEADD RESISTOR..2
(-5400 5450);
FORCEPROP 1 LAST $LOCATION R32
J 0
(-5350 5300);
DISPLAY 1.212766 (-5350 5300);
PAINT GREEN (-5350 5300);
FORCEPROP 0 LAST CDS_LOCATION R32
J 0
(-5350 5600);
DISPLAY 1.021277 (-5350 5600);
DISPLAY INVISIBLE (-5350 5600);
FORCEPROP 0 LAST $SEC 1
J 0
(-5350 5600);
DISPLAY 0.680851 (-5350 5600);
PAINT MONO (-5350 5600);
DISPLAY INVISIBLE (-5350 5600);
FORCEPROP 0 LAST CDS_SEC 1
J 0
(-5350 5600);
DISPLAY 1.021277 (-5350 5600);
DISPLAY INVISIBLE (-5350 5600);
FORCEPROP 0 LASTPIN (-5400 5550) $PN 1
R 1
J 0
(-5410 5560);
DISPLAY 0.680851 (-5410 5560);
PAINT MONO (-5410 5560);
FORCEPROP 0 LASTPIN (-5400 5300) $PN 2
R 1
J 2
(-5410 5290);
DISPLAY 0.680851 (-5410 5290);
PAINT MONO (-5410 5290);
FORCEPROP 0 LAST PACKAGE 0402
J 0
(-5350 5650);
DISPLAY 1.021277 (-5350 5650);
FORCEPROP 1 LAST VALUE 3.24KOHM
J 0
(-5350 5500);
DISPLAY 1.212766 (-5350 5500);
PAINT GREEN (-5350 5500);
FORCEPROP 1 LAST PATH I25
J 0
(-5597 5555);
DISPLAY 1.212766 (-5597 5555);
PAINT GREEN (-5597 5555);
DISPLAY INVISIBLE (-5597 5555);
FORCEPROP 1 LAST TOLERANCE 1%
J 0
(-5597 5705);
DISPLAY 1.212766 (-5597 5705);
PAINT GREEN (-5597 5705);
DISPLAY INVISIBLE (-5597 5705);
FORCEPROP 1 LAST CDS_LMAN_SYM_OUTLINE -50,50,50,-100
J 0
(-5400 5450);
DISPLAY 0.468085 (-5400 5450);
PAINT GREEN (-5400 5450);
DISPLAY INVISIBLE (-5400 5450);
FORCEPROP 2 LAST CDS_LIB passive
J 0
(-5400 5450);
DISPLAY INVISIBLE (-5400 5450);
FORCEPROP 1 LAST CLS_PN G155-03241-01
J 0
(-5536 5650);
DISPLAY 1.212766 (-5536 5650);
PAINT GREEN (-5536 5650);
DISPLAY INVISIBLE (-5536 5650);
FORCEADD RESISTOR..1
(-7100 7300);
FORCEPROP 1 LAST $LOCATION R31
J 2
(-7301 7305);
DISPLAY 1.212766 (-7301 7305);
PAINT GREEN (-7301 7305);
FORCEPROP 0 LAST CDS_LOCATION R31
J 0
(-6900 7400);
DISPLAY INVISIBLE (-6900 7400);
FORCEPROP 0 LAST $SEC 1
J 0
(-6900 7400);
DISPLAY 0.680851 (-6900 7400);
PAINT MONO (-6900 7400);
DISPLAY INVISIBLE (-6900 7400);
FORCEPROP 0 LAST CDS_SEC 1
J 0
(-6900 7400);
DISPLAY 1.021277 (-6900 7400);
DISPLAY INVISIBLE (-6900 7400);
FORCEPROP 0 LASTPIN (-7200 7300) $PN 1
J 2
(-7210 7310);
DISPLAY 0.680851 (-7210 7310);
PAINT MONO (-7210 7310);
FORCEPROP 0 LASTPIN (-6950 7300) $PN 2
J 0
(-6940 7310);
DISPLAY 0.680851 (-6940 7310);
PAINT MONO (-6940 7310);
FORCEPROP 1 LAST VALUE 0OHM
J 0
(-6850 7300);
DISPLAY 1.212766 (-6850 7300);
PAINT GREEN (-6850 7300);
FORCEPROP 0 LAST PACKAGE 0402
J 0
(-7150 7350);
DISPLAY 1.021277 (-7150 7350);
FORCEPROP 1 LAST PATH I26
J 0
(-7297 7405);
DISPLAY 1.212766 (-7297 7405);
PAINT GREEN (-7297 7405);
DISPLAY INVISIBLE (-7297 7405);
FORCEPROP 1 LAST TOLERANCE -
J 0
(-7297 7555);
DISPLAY 1.212766 (-7297 7555);
PAINT GREEN (-7297 7555);
DISPLAY INVISIBLE (-7297 7555);
FORCEPROP 1 LAST CLS_PN G155-100R0-J0
J 0
(-7236 7500);
DISPLAY 1.212766 (-7236 7500);
PAINT GREEN (-7236 7500);
DISPLAY INVISIBLE (-7236 7500);
FORCEPROP 1 LAST CDS_LMAN_SYM_OUTLINE -50,50,100,-50
J 0
(-7100 7300);
DISPLAY 0.468085 (-7100 7300);
PAINT GREEN (-7100 7300);
DISPLAY INVISIBLE (-7100 7300);
FORCEPROP 2 LAST CDS_LIB passive
J 0
(-7100 7300);
DISPLAY INVISIBLE (-7100 7300);
FORCEADD CAPACITOR..1
(-6200 7300);
FORCEPROP 1 LAST $LOCATION C44
J 2
(-6338 7300);
DISPLAY 1.212766 (-6338 7300);
PAINT GREEN (-6338 7300);
FORCEPROP 0 LAST CDS_LOCATION C44
J 0
(-5450 7500);
DISPLAY INVISIBLE (-5450 7500);
FORCEPROP 0 LAST $SEC 1
J 0
(-5950 7450);
DISPLAY 0.680851 (-5950 7450);
PAINT MONO (-5950 7450);
DISPLAY INVISIBLE (-5950 7450);
FORCEPROP 0 LAST CDS_SEC 1
J 0
(-5950 7450);
DISPLAY 1.021277 (-5950 7450);
DISPLAY INVISIBLE (-5950 7450);
FORCEPROP 0 LASTPIN (-6300 7300) $PN 1
J 2
(-6310 7310);
DISPLAY 0.680851 (-6310 7310);
PAINT MONO (-6310 7310);
FORCEPROP 0 LASTPIN (-6050 7300) $PN 2
J 0
(-6040 7310);
DISPLAY 0.680851 (-6040 7310);
PAINT MONO (-6040 7310);
FORCEPROP 0 LAST PACKAGE 0402
J 0
(-6250 7400);
DISPLAY 1.021277 (-6250 7400);
FORCEPROP 0 LAST VOLTAGE 25V
J 0
(-6250 7500);
DISPLAY 1.021277 (-6250 7500);
FORCEPROP 1 LAST VALUE 0.1UF
J 0
(-5950 7300);
DISPLAY 1.212766 (-5950 7300);
PAINT GREEN (-5950 7300);
FORCEPROP 1 LAST PATH I27
J 2
(-6250 7400);
DISPLAY 1.212766 (-6250 7400);
PAINT GREEN (-6250 7400);
DISPLAY INVISIBLE (-6250 7400);
FORCEPROP 2 LASTPIN (-6300 7300) SIG_NAME UN$516$CAPACITOR$I27$1
J 0
(-6290 7310);
DISPLAY 0.659574 (-6290 7310);
PAINT MONO (-6290 7310);
DISPLAY INVISIBLE (-6290 7310);
FORCEPROP 1 LAST CDS_LMAN_SYM_OUTLINE 0,50,50,-50
J 0
(-6200 7300);
DISPLAY 0.468085 (-6200 7300);
PAINT GREEN (-6200 7300);
DISPLAY INVISIBLE (-6200 7300);
FORCEPROP 2 LAST CDS_LIB passive
J 0
(-6200 7300);
DISPLAY INVISIBLE (-6200 7300);
FORCEPROP 1 LAST CLS_PN G105-0B104-EK
J 2
(-6250 7400);
DISPLAY 1.212766 (-6250 7400);
PAINT GREEN (-6250 7400);
DISPLAY INVISIBLE (-6250 7400);
FORCEPROP 1 LAST TOLERANCE 10%
J 2
(-6300 7400);
DISPLAY 1.212766 (-6300 7400);
PAINT GREEN (-6300 7400);
DISPLAY INVISIBLE (-6300 7400);
FORCEADD RESISTOR..1
R 1
(-4800 5400);
FORCEPROP 1 LAST $LOCATION R50
R 1
J 2
(-4855 5299);
DISPLAY 1.212766 (-4855 5299);
PAINT GREEN (-4855 5299);
FORCEPROP 0 LAST CDS_LOCATION R50
R 1
J 0
(-4650 5500);
DISPLAY 1.021277 (-4650 5500);
DISPLAY INVISIBLE (-4650 5500);
FORCEPROP 0 LAST $SEC 1
R 1
J 0
(-4650 5500);
DISPLAY 0.680851 (-4650 5500);
PAINT MONO (-4650 5500);
DISPLAY INVISIBLE (-4650 5500);
FORCEPROP 0 LAST CDS_SEC 1
R 1
J 0
(-4650 5500);
DISPLAY 1.021277 (-4650 5500);
DISPLAY INVISIBLE (-4650 5500);
FORCEPROP 0 LASTPIN (-4800 5300) $PN 1
R 1
J 2
(-4810 5290);
DISPLAY 0.680851 (-4810 5290);
PAINT MONO (-4810 5290);
FORCEPROP 0 LASTPIN (-4800 5550) $PN 2
R 1
J 0
(-4810 5560);
DISPLAY 0.680851 (-4810 5560);
PAINT MONO (-4810 5560);
FORCEPROP 1 LAST VALUE 0OHM
R 1
J 0
(-4700 5350);
DISPLAY 1.212766 (-4700 5350);
PAINT GREEN (-4700 5350);
FORCEPROP 0 LAST NO_ASSY TRUE
J 0
(-4650 5450);
DISPLAY 1.021277 (-4650 5450);
DISPLAY BOTH (-4650 5450);
FORCEPROP 0 LAST PACKAGE 0603
R 1
J 0
(-4600 5200);
DISPLAY 1.021277 (-4600 5200);
FORCEPROP 1 LAST PATH I28
R 1
J 0
(-4905 5203);
DISPLAY 1.212766 (-4905 5203);
PAINT GREEN (-4905 5203);
DISPLAY INVISIBLE (-4905 5203);
FORCEPROP 1 LAST TOLERANCE -
R 1
J 0
(-5055 5203);
DISPLAY 1.212766 (-5055 5203);
PAINT GREEN (-5055 5203);
DISPLAY INVISIBLE (-5055 5203);
FORCEPROP 2 LAST CDS_LIB passive
J 0
(-4800 5400);
DISPLAY INVISIBLE (-4800 5400);
FORCEPROP 1 LAST CDS_LMAN_SYM_OUTLINE -50,50,100,-50
R 1
J 0
(-4800 5400);
DISPLAY 0.468085 (-4800 5400);
PAINT GREEN (-4800 5400);
DISPLAY INVISIBLE (-4800 5400);
FORCEPROP 1 LAST CLS_PN G156-100R0-J0
R 1
J 0
(-5000 5264);
DISPLAY 1.212766 (-5000 5264);
PAINT GREEN (-5000 5264);
DISPLAY INVISIBLE (-5000 5264);
FORCEADD CAPACITOR..2
(-4000 6100);
FORCEPROP 1 LAST $LOCATION C11
J 0
(-3850 6150);
DISPLAY 1.212766 (-3850 6150);
PAINT GREEN (-3850 6150);
FORCEPROP 0 LAST CDS_LOCATION C11
J 0
(-3900 6350);
DISPLAY INVISIBLE (-3900 6350);
FORCEPROP 0 LAST $SEC 1
J 0
(-3950 6250);
DISPLAY 0.680851 (-3950 6250);
PAINT MONO (-3950 6250);
DISPLAY INVISIBLE (-3950 6250);
FORCEPROP 0 LAST CDS_SEC 1
J 0
(-3950 6250);
DISPLAY 1.021277 (-3950 6250);
DISPLAY INVISIBLE (-3950 6250);
FORCEPROP 0 LASTPIN (-4000 6200) $PN 1
R 1
J 0
(-4010 6210);
DISPLAY 0.680851 (-4010 6210);
PAINT MONO (-4010 6210);
FORCEPROP 0 LASTPIN (-4000 5950) $PN 2
R 1
J 2
(-4010 5940);
DISPLAY 0.680851 (-4010 5940);
PAINT MONO (-4010 5940);
FORCEPROP 0 LAST PACKAGE 0201
J 0
(-3850 5950);
DISPLAY 1.021277 (-3850 5950);
FORCEPROP 1 LAST VALUE 100PF
J 0
(-3850 6050);
DISPLAY 1.212766 (-3850 6050);
PAINT GREEN (-3850 6050);
FORCEPROP 0 LAST VOLTAGE 50V
J 0
(-3850 6300);
DISPLAY 1.021277 (-3850 6300);
FORCEPROP 1 LAST PATH I29
J 0
(-4100 6150);
DISPLAY 1.212766 (-4100 6150);
PAINT GREEN (-4100 6150);
DISPLAY INVISIBLE (-4100 6150);
FORCEPROP 2 LASTPIN (-4000 6200) SIG_NAME UN$516$CAPACITOR$I29$1
J 0
(-3990 6210);
DISPLAY 0.659574 (-3990 6210);
PAINT MONO (-3990 6210);
DISPLAY INVISIBLE (-3990 6210);
FORCEPROP 1 LAST CLS_PN G104-0B101-FK
J 0
(-4100 6150);
DISPLAY 1.212766 (-4100 6150);
PAINT GREEN (-4100 6150);
DISPLAY INVISIBLE (-4100 6150);
FORCEPROP 2 LAST CDS_LIB passive
J 0
(-4000 6100);
DISPLAY INVISIBLE (-4000 6100);
FORCEPROP 1 LAST CDS_LMAN_SYM_OUTLINE -50,0,50,-50
J 0
(-4000 6100);
DISPLAY 0.468085 (-4000 6100);
PAINT GREEN (-4000 6100);
DISPLAY INVISIBLE (-4000 6100);
FORCEPROP 1 LAST TOLERANCE 10%
J 0
(-4150 6200);
DISPLAY 1.212766 (-4150 6200);
PAINT GREEN (-4150 6200);
DISPLAY INVISIBLE (-4150 6200);
FORCEADD GND_SG..1
(-13750 7600);
FORCEPROP 3 LASTPIN (-13700 7650) SIG_NAME SG\g
J 0
(-13690 7660);
DISPLAY 0.659574 (-13690 7660);
PAINT MONO (-13690 7660);
DISPLAY INVISIBLE (-13690 7660);
FORCEPROP 1 LAST HDL_POWER SG
J 1
(-13695 7505);
DISPLAY 0.808511 (-13695 7505);
PAINT GREEN (-13695 7505);
FORCEPROP 1 LAST PATH I3
J 0
(-13715 7600);
DISPLAY 0.808511 (-13715 7600);
PAINT GREEN (-13715 7600);
DISPLAY INVISIBLE (-13715 7600);
FORCEPROP 1 LAST BODY_TYPE PLUMBING
J 0
(-13735 7585);
DISPLAY 0.808511 (-13735 7585);
PAINT GREEN (-13735 7585);
DISPLAY INVISIBLE (-13735 7585);
FORCEPROP 1 LAST CDS_LMAN_SYM_OUTLINE 0,0,100,-50
J 0
(-13750 7600);
DISPLAY 0.468085 (-13750 7600);
PAINT GREEN (-13750 7600);
DISPLAY INVISIBLE (-13750 7600);
FORCEPROP 2 LAST CDS_LIB cls
J 0
(-13750 7600);
DISPLAY INVISIBLE (-13750 7600);
FORCEADD RESISTOR..2
(-3350 6150);
FORCEPROP 1 LAST $LOCATION R34
J 0
(-3300 6000);
DISPLAY 1.212766 (-3300 6000);
PAINT GREEN (-3300 6000);
FORCEPROP 0 LAST CDS_LOCATION R34
J 0
(-3300 6300);
DISPLAY INVISIBLE (-3300 6300);
FORCEPROP 0 LAST $SEC 1
J 0
(-3300 6300);
DISPLAY 0.680851 (-3300 6300);
PAINT MONO (-3300 6300);
DISPLAY INVISIBLE (-3300 6300);
FORCEPROP 0 LAST CDS_SEC 1
J 0
(-3300 6300);
DISPLAY 1.021277 (-3300 6300);
DISPLAY INVISIBLE (-3300 6300);
FORCEPROP 0 LASTPIN (-3350 6250) $PN 1
R 1
J 0
(-3360 6260);
DISPLAY 0.680851 (-3360 6260);
PAINT MONO (-3360 6260);
FORCEPROP 0 LASTPIN (-3350 6000) $PN 2
R 1
J 2
(-3360 5990);
DISPLAY 0.680851 (-3360 5990);
PAINT MONO (-3360 5990);
FORCEPROP 0 LAST PACKAGE 0402
J 0
(-3300 6350);
DISPLAY 1.021277 (-3300 6350);
FORCEPROP 1 LAST VALUE 24KOHM
J 0
(-3300 6200);
DISPLAY 1.212766 (-3300 6200);
PAINT GREEN (-3300 6200);
FORCEPROP 1 LAST PATH I30
J 0
(-3547 6255);
DISPLAY 1.212766 (-3547 6255);
PAINT GREEN (-3547 6255);
DISPLAY INVISIBLE (-3547 6255);
FORCEPROP 1 LAST TOLERANCE 1%
J 0
(-3547 6405);
DISPLAY 1.212766 (-3547 6405);
PAINT GREEN (-3547 6405);
DISPLAY INVISIBLE (-3547 6405);
FORCEPROP 1 LAST CDS_LMAN_SYM_OUTLINE -50,50,50,-100
J 0
(-3350 6150);
DISPLAY 0.468085 (-3350 6150);
PAINT GREEN (-3350 6150);
DISPLAY INVISIBLE (-3350 6150);
FORCEPROP 2 LAST CDS_LIB passive
J 0
(-3350 6150);
DISPLAY INVISIBLE (-3350 6150);
FORCEPROP 1 LAST CLS_PN G155-02402-01
J 0
(-3486 6350);
DISPLAY 1.212766 (-3486 6350);
PAINT GREEN (-3486 6350);
DISPLAY INVISIBLE (-3486 6350);
FORCEADD RESISTOR..2
(-3350 6700);
FORCEPROP 1 LAST $LOCATION R6
J 0
(-3300 6550);
DISPLAY 1.212766 (-3300 6550);
PAINT GREEN (-3300 6550);
FORCEPROP 0 LAST CDS_LOCATION R6
J 0
(-3300 6850);
DISPLAY INVISIBLE (-3300 6850);
FORCEPROP 0 LAST $SEC 1
J 0
(-3300 6850);
DISPLAY 0.680851 (-3300 6850);
PAINT MONO (-3300 6850);
DISPLAY INVISIBLE (-3300 6850);
FORCEPROP 0 LAST CDS_SEC 1
J 0
(-3300 6850);
DISPLAY 1.021277 (-3300 6850);
DISPLAY INVISIBLE (-3300 6850);
FORCEPROP 0 LASTPIN (-3350 6800) $PN 1
R 1
J 0
(-3360 6810);
DISPLAY 0.680851 (-3360 6810);
PAINT MONO (-3360 6810);
FORCEPROP 0 LASTPIN (-3350 6550) $PN 2
R 1
J 2
(-3360 6540);
DISPLAY 0.680851 (-3360 6540);
PAINT MONO (-3360 6540);
FORCEPROP 1 LAST VALUE 20OHM
J 0
(-3300 6750);
DISPLAY 1.212766 (-3300 6750);
PAINT GREEN (-3300 6750);
FORCEPROP 0 LAST PACKAGE 0402
J 0
(-3300 6900);
DISPLAY 1.021277 (-3300 6900);
FORCEPROP 1 LAST PATH I31
J 0
(-3547 6805);
DISPLAY 1.212766 (-3547 6805);
PAINT GREEN (-3547 6805);
DISPLAY INVISIBLE (-3547 6805);
FORCEPROP 1 LAST TOLERANCE 1%
J 0
(-3547 6955);
DISPLAY 1.212766 (-3547 6955);
PAINT GREEN (-3547 6955);
DISPLAY INVISIBLE (-3547 6955);
FORCEPROP 1 LAST CLS_PN G155-120R0-01
J 0
(-3486 6900);
DISPLAY 1.212766 (-3486 6900);
PAINT GREEN (-3486 6900);
DISPLAY INVISIBLE (-3486 6900);
FORCEPROP 2 LAST CDS_LIB passive
J 0
(-3350 6700);
DISPLAY INVISIBLE (-3350 6700);
FORCEPROP 1 LAST CDS_LMAN_SYM_OUTLINE -50,50,50,-100
J 0
(-3350 6700);
DISPLAY 0.468085 (-3350 6700);
PAINT GREEN (-3350 6700);
DISPLAY INVISIBLE (-3350 6700);
FORCEADD CAPACITOR..2
(-2700 6750);
FORCEPROP 1 LAST $LOCATION C12
J 0
(-2600 6800);
DISPLAY 1.212766 (-2600 6800);
PAINT GREEN (-2600 6800);
FORCEPROP 0 LAST CDS_LOCATION C12
J 0
(-2600 7000);
DISPLAY INVISIBLE (-2600 7000);
FORCEPROP 0 LAST $SEC 1
J 0
(-2650 6900);
DISPLAY 0.680851 (-2650 6900);
PAINT MONO (-2650 6900);
DISPLAY INVISIBLE (-2650 6900);
FORCEPROP 0 LAST CDS_SEC 1
J 0
(-2650 6900);
DISPLAY 1.021277 (-2650 6900);
DISPLAY INVISIBLE (-2650 6900);
FORCEPROP 0 LASTPIN (-2700 6850) $PN 1
R 1
J 0
(-2710 6860);
DISPLAY 0.680851 (-2710 6860);
PAINT MONO (-2710 6860);
FORCEPROP 0 LASTPIN (-2700 6600) $PN 2
R 1
J 2
(-2710 6590);
DISPLAY 0.680851 (-2710 6590);
PAINT MONO (-2710 6590);
FORCEPROP 1 LAST VALUE 0.1UF
J 0
(-2600 6700);
DISPLAY 1.212766 (-2600 6700);
PAINT GREEN (-2600 6700);
FORCEPROP 0 LAST PACKAGE 0402
J 0
(-2600 6950);
DISPLAY 1.021277 (-2600 6950);
FORCEPROP 0 LAST VOLTAGE 10V
J 0
(-2600 7050);
DISPLAY 1.021277 (-2600 7050);
FORCEPROP 1 LAST PATH I32
J 0
(-2800 6800);
DISPLAY 1.212766 (-2800 6800);
PAINT GREEN (-2800 6800);
DISPLAY INVISIBLE (-2800 6800);
FORCEPROP 1 LAST TOLERANCE 10%
J 0
(-2850 6850);
DISPLAY 1.212766 (-2850 6850);
PAINT GREEN (-2850 6850);
DISPLAY INVISIBLE (-2850 6850);
FORCEPROP 1 LAST CDS_LMAN_SYM_OUTLINE -50,0,50,-50
J 0
(-2700 6750);
DISPLAY 0.468085 (-2700 6750);
PAINT GREEN (-2700 6750);
DISPLAY INVISIBLE (-2700 6750);
FORCEPROP 2 LAST CDS_LIB passive
J 0
(-2700 6750);
DISPLAY INVISIBLE (-2700 6750);
FORCEPROP 1 LAST CLS_PN G105-0B104-CK
J 0
(-2800 6800);
DISPLAY 1.212766 (-2800 6800);
PAINT GREEN (-2800 6800);
DISPLAY INVISIBLE (-2800 6800);
FORCEADD CAPACITOR..2
(-2150 6750);
FORCEPROP 1 LAST $LOCATION C13
J 0
(-2050 6800);
DISPLAY 1.212766 (-2050 6800);
PAINT GREEN (-2050 6800);
FORCEPROP 0 LAST CDS_LOCATION C13
J 0
(-2050 7000);
DISPLAY INVISIBLE (-2050 7000);
FORCEPROP 0 LAST $SEC 1
J 0
(-2100 6900);
DISPLAY INVISIBLE (-2100 6900);
FORCEPROP 0 LAST CDS_SEC 1
J 0
(-2100 6900);
DISPLAY INVISIBLE (-2100 6900);
FORCEPROP 0 LASTPIN (-2150 6850) $PN 1
R 1
J 0
(-2160 6860);
DISPLAY 0.808511 (-2160 6860);
FORCEPROP 0 LASTPIN (-2150 6600) $PN 2
R 1
J 2
(-2160 6590);
DISPLAY 0.808511 (-2160 6590);
FORCEPROP 0 LAST PACKAGE 0805
J 0
(-2050 6950);
DISPLAY 1.021277 (-2050 6950);
FORCEPROP 1 LAST VALUE 22UF
J 0
(-2050 6700);
DISPLAY 1.212766 (-2050 6700);
PAINT GREEN (-2050 6700);
FORCEPROP 0 LAST VOLTAGE 10V
J 0
(-2050 7050);
DISPLAY 1.021277 (-2050 7050);
FORCEPROP 1 LAST PATH I33
J 0
(-2250 6800);
DISPLAY 1.212766 (-2250 6800);
PAINT GREEN (-2250 6800);
DISPLAY INVISIBLE (-2250 6800);
FORCEPROP 1 LAST CLS_PN G107-0F226-CM
J 0
(-2250 6800);
DISPLAY 1.212766 (-2250 6800);
PAINT GREEN (-2250 6800);
DISPLAY INVISIBLE (-2250 6800);
FORCEPROP 2 LAST CDS_LIB passive
J 0
(-2150 6750);
DISPLAY INVISIBLE (-2150 6750);
FORCEPROP 1 LAST CDS_LMAN_SYM_OUTLINE -50,0,50,-50
J 0
(-2150 6750);
DISPLAY 0.468085 (-2150 6750);
PAINT GREEN (-2150 6750);
DISPLAY INVISIBLE (-2150 6750);
FORCEPROP 1 LAST TOLERANCE 20%
J 0
(-2300 6850);
DISPLAY 1.212766 (-2300 6850);
PAINT GREEN (-2300 6850);
DISPLAY INVISIBLE (-2300 6850);
FORCEADD GND_SG..1
(-1200 6200);
FORCEPROP 3 LASTPIN (-1150 6250) SIG_NAME SG\g
J 0
(-1140 6260);
DISPLAY 0.659574 (-1140 6260);
PAINT MONO (-1140 6260);
DISPLAY INVISIBLE (-1140 6260);
FORCEPROP 1 LAST HDL_POWER SG
J 1
(-1145 6105);
DISPLAY 0.808511 (-1145 6105);
PAINT GREEN (-1145 6105);
FORCEPROP 1 LAST PATH I34
J 0
(-1165 6200);
DISPLAY 0.808511 (-1165 6200);
PAINT GREEN (-1165 6200);
DISPLAY INVISIBLE (-1165 6200);
FORCEPROP 1 LAST BODY_TYPE PLUMBING
J 0
(-1185 6185);
DISPLAY 0.808511 (-1185 6185);
PAINT GREEN (-1185 6185);
DISPLAY INVISIBLE (-1185 6185);
FORCEPROP 1 LAST CDS_LMAN_SYM_OUTLINE 0,0,100,-50
J 0
(-1200 6200);
DISPLAY 0.468085 (-1200 6200);
PAINT GREEN (-1200 6200);
DISPLAY INVISIBLE (-1200 6200);
FORCEPROP 2 LAST CDS_LIB cls
J 0
(-1200 6200);
DISPLAY INVISIBLE (-1200 6200);
FORCEADD CAPACITOR..2
(-1650 6750);
FORCEPROP 1 LAST $LOCATION C14
J 0
(-1550 6800);
DISPLAY 1.212766 (-1550 6800);
PAINT GREEN (-1550 6800);
FORCEPROP 0 LAST CDS_LOCATION C14
J 0
(-1550 7000);
DISPLAY INVISIBLE (-1550 7000);
FORCEPROP 0 LAST $SEC 1
J 0
(-1600 6900);
DISPLAY INVISIBLE (-1600 6900);
FORCEPROP 0 LAST CDS_SEC 1
J 0
(-1600 6900);
DISPLAY INVISIBLE (-1600 6900);
FORCEPROP 0 LASTPIN (-1650 6850) $PN 1
R 1
J 0
(-1660 6860);
DISPLAY 0.808511 (-1660 6860);
FORCEPROP 0 LASTPIN (-1650 6600) $PN 2
R 1
J 2
(-1660 6590);
DISPLAY 0.808511 (-1660 6590);
FORCEPROP 1 LAST VALUE 22UF
J 0
(-1550 6700);
DISPLAY 1.212766 (-1550 6700);
PAINT GREEN (-1550 6700);
FORCEPROP 0 LAST PACKAGE 0805
J 0
(-1550 6950);
DISPLAY 1.021277 (-1550 6950);
FORCEPROP 0 LAST VOLTAGE 10V
J 0
(-1550 7050);
DISPLAY 1.021277 (-1550 7050);
FORCEPROP 1 LAST PATH I35
J 0
(-1750 6800);
DISPLAY 1.212766 (-1750 6800);
PAINT GREEN (-1750 6800);
DISPLAY INVISIBLE (-1750 6800);
FORCEPROP 1 LAST CDS_LMAN_SYM_OUTLINE -50,0,50,-50
J 0
(-1650 6750);
DISPLAY 0.468085 (-1650 6750);
PAINT GREEN (-1650 6750);
DISPLAY INVISIBLE (-1650 6750);
FORCEPROP 2 LAST CDS_LIB passive
J 0
(-1650 6750);
DISPLAY INVISIBLE (-1650 6750);
FORCEPROP 1 LAST CLS_PN G107-0F226-CM
J 0
(-1750 6800);
DISPLAY 1.212766 (-1750 6800);
PAINT GREEN (-1750 6800);
DISPLAY INVISIBLE (-1750 6800);
FORCEPROP 1 LAST TOLERANCE 20%
J 0
(-1800 6850);
DISPLAY 1.212766 (-1800 6850);
PAINT GREEN (-1800 6850);
DISPLAY INVISIBLE (-1800 6850);
FORCEADD INDUCTOR_2..1
(-4850 7100);
FORCEPROP 1 LAST $LOCATION L1
J 2
(-5050 7100);
DISPLAY 1.212766 (-5050 7100);
PAINT GREEN (-5050 7100);
FORCEPROP 0 LAST CDS_LOCATION L1
J 0
(-4600 7200);
DISPLAY INVISIBLE (-4600 7200);
FORCEPROP 0 LAST $SEC 1
J 0
(-4650 7250);
DISPLAY 0.680851 (-4650 7250);
PAINT MONO (-4650 7250);
DISPLAY INVISIBLE (-4650 7250);
FORCEPROP 0 LAST CDS_SEC 1
J 0
(-4650 7250);
DISPLAY 1.021277 (-4650 7250);
DISPLAY INVISIBLE (-4650 7250);
FORCEPROP 0 LASTPIN (-5000 7100) $PN 1
J 2
(-5010 7110);
DISPLAY 0.680851 (-5010 7110);
PAINT MONO (-5010 7110);
FORCEPROP 0 LASTPIN (-4650 7100) $PN 2
J 0
(-4640 7110);
DISPLAY 0.680851 (-4640 7110);
PAINT MONO (-4640 7110);
FORCEPROP 1 LAST VALUE 4.7UH
J 0
(-4600 7100);
DISPLAY 1.212766 (-4600 7100);
PAINT GREEN (-4600 7100);
FORCEPROP 1 LAST PATH I36
J 2
(-4898 7010);
DISPLAY 1.212766 (-4898 7010);
PAINT GREEN (-4898 7010);
DISPLAY INVISIBLE (-4898 7010);
FORCEPROP 2 LAST CDS_LIB passive
J 0
(-4850 7100);
DISPLAY INVISIBLE (-4850 7100);
FORCEPROP 1 LAST CDS_LMAN_SYM_OUTLINE -100,50,150,-50
J 0
(-4850 7100);
DISPLAY 0.468085 (-4850 7100);
PAINT GREEN (-4850 7100);
DISPLAY INVISIBLE (-4850 7100);
FORCEPROP 1 LAST CLS_PN G190-10424-01
J 2
(-4894 7250);
DISPLAY 1.212766 (-4894 7250);
PAINT GREEN (-4894 7250);
DISPLAY INVISIBLE (-4894 7250);
FORCEPROP 1 LAST TOLERANCE 20%
J 2
(-4644 7000);
DISPLAY 1.212766 (-4644 7000);
PAINT GREEN (-4644 7000);
DISPLAY INVISIBLE (-4644 7000);
FORCEADD CAPACITOR..1
(-4900 7450);
FORCEPROP 1 LAST $LOCATION C45
J 2
(-5000 7450);
DISPLAY 1.212766 (-5000 7450);
PAINT GREEN (-5000 7450);
FORCEPROP 0 LAST CDS_LOCATION C45
J 0
(-3650 7550);
DISPLAY INVISIBLE (-3650 7550);
FORCEPROP 0 LAST $SEC 1
J 0
(-4650 7600);
DISPLAY 0.680851 (-4650 7600);
PAINT MONO (-4650 7600);
DISPLAY INVISIBLE (-4650 7600);
FORCEPROP 0 LAST CDS_SEC 1
J 0
(-4650 7600);
DISPLAY 1.021277 (-4650 7600);
DISPLAY INVISIBLE (-4650 7600);
FORCEPROP 0 LASTPIN (-5000 7450) $PN 1
J 2
(-5010 7460);
DISPLAY 0.680851 (-5010 7460);
PAINT MONO (-5010 7460);
FORCEPROP 0 LASTPIN (-4750 7450) $PN 2
J 0
(-4740 7460);
DISPLAY 0.680851 (-4740 7460);
PAINT MONO (-4740 7460);
FORCEPROP 0 LAST PACKAGE 0402
J 0
(-4950 7550);
DISPLAY 1.021277 (-4950 7550);
FORCEPROP 1 LAST VALUE 1000PF
J 0
(-4600 7450);
DISPLAY 1.212766 (-4600 7450);
PAINT GREEN (-4600 7450);
FORCEPROP 0 LAST VOLTAGE 50V
J 0
(-4950 7650);
DISPLAY 1.021277 (-4950 7650);
FORCEPROP 0 LAST NO_ASSY TRUE
J 0
(-5100 7300);
DISPLAY 1.021277 (-5100 7300);
DISPLAY BOTH (-5100 7300);
FORCEPROP 1 LAST PATH I37
J 2
(-4950 7550);
DISPLAY 1.212766 (-4950 7550);
PAINT GREEN (-4950 7550);
DISPLAY INVISIBLE (-4950 7550);
FORCEPROP 1 LAST TOLERANCE 5%
J 2
(-5000 7550);
DISPLAY 1.212766 (-5000 7550);
PAINT GREEN (-5000 7550);
DISPLAY INVISIBLE (-5000 7550);
FORCEPROP 1 LAST CLS_PN G105-0A102-FJ
J 2
(-4950 7550);
DISPLAY 1.212766 (-4950 7550);
PAINT GREEN (-4950 7550);
DISPLAY INVISIBLE (-4950 7550);
FORCEPROP 2 LAST CDS_LIB passive
J 0
(-4900 7450);
DISPLAY INVISIBLE (-4900 7450);
FORCEPROP 1 LAST CDS_LMAN_SYM_OUTLINE 0,50,50,-50
J 0
(-4900 7450);
DISPLAY 0.468085 (-4900 7450);
PAINT GREEN (-4900 7450);
DISPLAY INVISIBLE (-4900 7450);
FORCEPROP 2 LASTPIN (-4750 7450) SIG_NAME UN$516$CAPACITOR$I37$2
J 0
(-4740 7460);
DISPLAY 0.659574 (-4740 7460);
PAINT MONO (-4740 7460);
DISPLAY INVISIBLE (-4740 7460);
FORCEADD RESISTOR..1
(-3950 7450);
FORCEPROP 1 LAST $LOCATION R33
J 2
(-4150 7450);
DISPLAY 1.212766 (-4150 7450);
PAINT GREEN (-4150 7450);
FORCEPROP 0 LAST CDS_LOCATION R33
J 0
(-3700 7550);
DISPLAY INVISIBLE (-3700 7550);
FORCEPROP 0 LAST $SEC 1
J 0
(-3800 7600);
DISPLAY 0.680851 (-3800 7600);
PAINT MONO (-3800 7600);
DISPLAY INVISIBLE (-3800 7600);
FORCEPROP 0 LAST CDS_SEC 1
J 0
(-3800 7600);
DISPLAY 1.021277 (-3800 7600);
DISPLAY INVISIBLE (-3800 7600);
FORCEPROP 0 LASTPIN (-4050 7450) $PN 1
J 2
(-4060 7460);
DISPLAY 0.680851 (-4060 7460);
PAINT MONO (-4060 7460);
FORCEPROP 0 LASTPIN (-3800 7450) $PN 2
J 0
(-3790 7460);
DISPLAY 0.680851 (-3790 7460);
PAINT MONO (-3790 7460);
FORCEPROP 0 LAST PACKAGE 0805
J 0
(-4000 7500);
DISPLAY 1.021277 (-4000 7500);
FORCEPROP 1 LAST VALUE 2.2OHM
J 0
(-3700 7450);
DISPLAY 1.212766 (-3700 7450);
PAINT GREEN (-3700 7450);
FORCEPROP 0 LAST NO_ASSY TRUE
J 0
(-4150 7300);
DISPLAY 1.021277 (-4150 7300);
DISPLAY BOTH (-4150 7300);
FORCEPROP 1 LAST PATH I38
J 0
(-4147 7555);
DISPLAY 1.212766 (-4147 7555);
PAINT GREEN (-4147 7555);
DISPLAY INVISIBLE (-4147 7555);
FORCEPROP 1 LAST TOLERANCE 1%
J 0
(-4147 7705);
DISPLAY 1.212766 (-4147 7705);
PAINT GREEN (-4147 7705);
DISPLAY INVISIBLE (-4147 7705);
FORCEPROP 1 LAST CDS_LMAN_SYM_OUTLINE -50,50,100,-50
J 0
(-3950 7450);
DISPLAY 0.468085 (-3950 7450);
PAINT GREEN (-3950 7450);
DISPLAY INVISIBLE (-3950 7450);
FORCEPROP 2 LAST CDS_LIB passive
J 0
(-3950 7450);
DISPLAY INVISIBLE (-3950 7450);
FORCEPROP 1 LAST CLS_PN G157-12R20-01
J 0
(-4086 7650);
DISPLAY 1.212766 (-4086 7650);
PAINT GREEN (-4086 7650);
DISPLAY INVISIBLE (-4086 7650);
FORCEADD GND_SG..1
(-3450 7300);
FORCEPROP 3 LASTPIN (-3400 7350) SIG_NAME SG\g
J 0
(-3390 7360);
DISPLAY 0.659574 (-3390 7360);
PAINT MONO (-3390 7360);
DISPLAY INVISIBLE (-3390 7360);
FORCEPROP 1 LAST HDL_POWER SG
J 1
(-3395 7205);
DISPLAY 0.808511 (-3395 7205);
PAINT GREEN (-3395 7205);
FORCEPROP 1 LAST PATH I39
J 0
(-3415 7300);
DISPLAY 0.808511 (-3415 7300);
PAINT GREEN (-3415 7300);
DISPLAY INVISIBLE (-3415 7300);
FORCEPROP 1 LAST BODY_TYPE PLUMBING
J 0
(-3435 7285);
DISPLAY 0.808511 (-3435 7285);
PAINT GREEN (-3435 7285);
DISPLAY INVISIBLE (-3435 7285);
FORCEPROP 1 LAST CDS_LMAN_SYM_OUTLINE 0,0,100,-50
J 0
(-3450 7300);
DISPLAY 0.468085 (-3450 7300);
PAINT GREEN (-3450 7300);
DISPLAY INVISIBLE (-3450 7300);
FORCEPROP 2 LAST CDS_LIB cls
J 0
(-3450 7300);
DISPLAY INVISIBLE (-3450 7300);
FORCEADD CAPACITOR..2
(-13700 8000);
FORCEPROP 1 LAST $LOCATION C74
J 0
(-13600 8000);
DISPLAY 1.212766 (-13600 8000);
PAINT GREEN (-13600 8000);
FORCEPROP 0 LAST CDS_LOCATION C74
J 0
(-13600 8250);
DISPLAY 1.021277 (-13600 8250);
DISPLAY INVISIBLE (-13600 8250);
FORCEPROP 0 LAST $SEC 1
J 0
(-13600 8250);
DISPLAY 0.680851 (-13600 8250);
PAINT MONO (-13600 8250);
DISPLAY INVISIBLE (-13600 8250);
FORCEPROP 0 LAST CDS_SEC 1
J 0
(-13600 8250);
DISPLAY 1.021277 (-13600 8250);
DISPLAY INVISIBLE (-13600 8250);
FORCEPROP 0 LASTPIN (-13700 8100) $PN 1
R 1
J 0
(-13710 8110);
DISPLAY 0.680851 (-13710 8110);
PAINT MONO (-13710 8110);
FORCEPROP 0 LASTPIN (-13700 7850) $PN 2
R 1
J 2
(-13710 7840);
DISPLAY 0.680851 (-13710 7840);
PAINT MONO (-13710 7840);
FORCEPROP 0 LAST PACKAGE 0402
J 0
(-13600 7800);
DISPLAY 1.021277 (-13600 7800);
FORCEPROP 1 LAST VALUE 0.1UF
J 0
(-13600 7900);
DISPLAY 1.212766 (-13600 7900);
PAINT GREEN (-13600 7900);
FORCEPROP 0 LAST VOLTAGE 25V
J 0
(-13600 8100);
DISPLAY 1.021277 (-13600 8100);
FORCEPROP 1 LAST PATH I4
J 0
(-13800 8050);
DISPLAY 1.212766 (-13800 8050);
PAINT GREEN (-13800 8050);
DISPLAY INVISIBLE (-13800 8050);
FORCEPROP 1 LAST CDS_LMAN_SYM_OUTLINE -50,0,50,-50
J 0
(-13700 8000);
DISPLAY 0.468085 (-13700 8000);
PAINT GREEN (-13700 8000);
DISPLAY INVISIBLE (-13700 8000);
FORCEPROP 2 LAST CDS_LIB passive
J 0
(-13700 8000);
DISPLAY INVISIBLE (-13700 8000);
FORCEPROP 1 LAST CLS_PN G105-0B104-EK
J 0
(-13800 8050);
DISPLAY 1.212766 (-13800 8050);
PAINT GREEN (-13800 8050);
DISPLAY INVISIBLE (-13800 8050);
FORCEPROP 1 LAST TOLERANCE 10%
J 0
(-13850 8100);
DISPLAY 1.212766 (-13850 8100);
PAINT GREEN (-13850 8100);
DISPLAY INVISIBLE (-13850 8100);
FORCEADD CAPACITOR..2
(-1150 6750);
FORCEPROP 1 LAST $LOCATION C15
J 0
(-1050 6800);
DISPLAY 1.212766 (-1050 6800);
PAINT GREEN (-1050 6800);
FORCEPROP 0 LAST CDS_LOCATION C15
J 0
(-1050 7000);
DISPLAY INVISIBLE (-1050 7000);
FORCEPROP 0 LAST $SEC 1
J 0
(-1050 7000);
DISPLAY INVISIBLE (-1050 7000);
FORCEPROP 0 LAST CDS_SEC 1
J 0
(-1050 7000);
DISPLAY INVISIBLE (-1050 7000);
FORCEPROP 0 LASTPIN (-1150 6850) $PN 1
R 1
J 0
(-1160 6860);
DISPLAY 0.808511 (-1160 6860);
FORCEPROP 0 LASTPIN (-1150 6600) $PN 2
R 1
J 2
(-1160 6590);
DISPLAY 0.808511 (-1160 6590);
FORCEPROP 0 LAST PACKAGE 0805
J 0
(-1050 6950);
DISPLAY 1.021277 (-1050 6950);
FORCEPROP 1 LAST VALUE 22UF
J 0
(-1050 6700);
DISPLAY 1.212766 (-1050 6700);
PAINT GREEN (-1050 6700);
FORCEPROP 0 LAST VOLTAGE 10V
J 0
(-1050 7050);
DISPLAY 1.021277 (-1050 7050);
FORCEPROP 1 LAST PATH I40
J 0
(-1250 6800);
DISPLAY 1.212766 (-1250 6800);
PAINT GREEN (-1250 6800);
DISPLAY INVISIBLE (-1250 6800);
FORCEPROP 2 LAST CDS_LIB passive
J 0
(-1150 6750);
DISPLAY INVISIBLE (-1150 6750);
FORCEPROP 1 LAST CDS_LMAN_SYM_OUTLINE -50,0,50,-50
J 0
(-1150 6750);
DISPLAY 0.468085 (-1150 6750);
PAINT GREEN (-1150 6750);
DISPLAY INVISIBLE (-1150 6750);
FORCEPROP 1 LAST CLS_PN G107-0F226-CM
J 0
(-1250 6800);
DISPLAY 1.212766 (-1250 6800);
PAINT GREEN (-1250 6800);
DISPLAY INVISIBLE (-1250 6800);
FORCEPROP 1 LAST TOLERANCE 20%
J 0
(-1300 6850);
DISPLAY 1.212766 (-1300 6850);
PAINT GREEN (-1300 6850);
DISPLAY INVISIBLE (-1300 6850);
FORCEADD VCC..1
(-1050 7350);
FORCEPROP 3 LASTPIN (-1000 7300) SIG_NAME XP5R0V\g
J 0
(-990 7310);
DISPLAY 0.659574 (-990 7310);
PAINT MONO (-990 7310);
DISPLAY INVISIBLE (-990 7310);
FORCEPROP 1 LAST HDL_POWER XP5R0V
J 1
(-995 7405);
DISPLAY 1.021277 (-995 7405);
PAINT GREEN (-995 7405);
FORCEPROP 0 LAST VOLTAGE 5.0
J 0
(-1200 7500);
DISPLAY 1.021277 (-1200 7500);
DISPLAY BOTH (-1200 7500);
FORCEPROP 1 LAST PATH I41
J 0
(-1015 7440);
DISPLAY 0.808511 (-1015 7440);
PAINT GREEN (-1015 7440);
DISPLAY INVISIBLE (-1015 7440);
FORCEPROP 1 LAST BODY_TYPE PLUMBING
J 0
(-1095 7307);
DISPLAY 0.340426 (-1095 7307);
PAINT GREEN (-1095 7307);
DISPLAY INVISIBLE (-1095 7307);
FORCEPROP 2 LAST CDS_LIB cls
J 0
(-1050 7350);
DISPLAY INVISIBLE (-1050 7350);
FORCEPROP 1 LAST CDS_LMAN_SYM_OUTLINE -250,250,250,-250
J 0
(-1050 7350);
DISPLAY 0.468085 (-1050 7350);
PAINT GREEN (-1050 7350);
DISPLAY INVISIBLE (-1050 7350);
FORCEADD TPS54824RNVR_VQFN18..1
(-9450 7400);
FORCEPROP 1 LAST $LOCATION U5
J 0
(-9400 7500);
DISPLAY 1.212766 (-9400 7500);
PAINT GREEN (-9400 7500);
FORCEPROP 0 LAST CDS_LOCATION U5
J 0
(-9400 7500);
DISPLAY 1.212766 (-9400 7500);
PAINT GREEN (-9400 7500);
DISPLAY INVISIBLE (-9400 7500);
FORCEPROP 0 LAST $SEC 1
J 0
(-9400 7800);
DISPLAY 0.680851 (-9400 7800);
PAINT MONO (-9400 7800);
DISPLAY INVISIBLE (-9400 7800);
FORCEPROP 0 LAST CDS_SEC 1
J 0
(-9400 7800);
DISPLAY 1.021277 (-9400 7800);
DISPLAY INVISIBLE (-9400 7800);
FORCEPROP 0 LASTPIN (-9550 5800) $PN 12
J 2
(-9560 5810);
DISPLAY 0.680851 (-9560 5810);
PAINT MONO (-9560 5810);
FORCEPROP 0 LASTPIN (-8350 7300) $PN 1
J 0
(-8340 7310);
DISPLAY 0.680851 (-8340 7310);
PAINT MONO (-8340 7310);
FORCEPROP 0 LASTPIN (-9550 6200) $PN 15
J 2
(-9560 6210);
DISPLAY 0.680851 (-9560 6210);
PAINT MONO (-9560 6210);
FORCEPROP 0 LASTPIN (-9550 7000) $PN 17
J 2
(-9560 7010);
DISPLAY 0.680851 (-9560 7010);
PAINT MONO (-9560 7010);
FORCEPROP 0 LASTPIN (-8350 6600) $PN 14
J 0
(-8340 6610);
DISPLAY 0.680851 (-8340 6610);
PAINT MONO (-8340 6610);
FORCEPROP 0 LASTPIN (-8350 6300) $PN 3
J 0
(-8340 6310);
DISPLAY 0.680851 (-8340 6310);
PAINT MONO (-8340 6310);
FORCEPROP 0 LASTPIN (-8350 6200) $PN 4
J 0
(-8340 6210);
DISPLAY 0.680851 (-8340 6210);
PAINT MONO (-8340 6210);
FORCEPROP 0 LASTPIN (-8350 6100) $PN 5
J 0
(-8340 6110);
DISPLAY 0.680851 (-8340 6110);
PAINT MONO (-8340 6110);
FORCEPROP 0 LASTPIN (-8350 6000) $PN 8
J 0
(-8340 6010);
DISPLAY 0.680851 (-8340 6010);
PAINT MONO (-8340 6010);
FORCEPROP 0 LASTPIN (-8350 5900) $PN 9
J 0
(-8340 5910);
DISPLAY 0.680851 (-8340 5910);
PAINT MONO (-8340 5910);
FORCEPROP 0 LASTPIN (-8350 5800) $PN 10
J 0
(-8340 5810);
DISPLAY 0.680851 (-8340 5810);
PAINT MONO (-8340 5810);
FORCEPROP 0 LASTPIN (-9550 6800) $PN 18
J 2
(-9560 6810);
DISPLAY 0.680851 (-9560 6810);
PAINT MONO (-9560 6810);
FORCEPROP 0 LASTPIN (-9550 6400) $PN 13
J 2
(-9560 6410);
DISPLAY 0.680851 (-9560 6410);
PAINT MONO (-9560 6410);
FORCEPROP 0 LASTPIN (-9550 6600) $PN 16
J 2
(-9560 6610);
DISPLAY 0.680851 (-9560 6610);
PAINT MONO (-9560 6610);
FORCEPROP 0 LASTPIN (-8350 7100) $PN 6
J 0
(-8340 7110);
DISPLAY 0.680851 (-8340 7110);
PAINT MONO (-8340 7110);
FORCEPROP 0 LASTPIN (-8350 7000) $PN 7
J 0
(-8340 7010);
DISPLAY 0.680851 (-8340 7010);
PAINT MONO (-8340 7010);
FORCEPROP 0 LASTPIN (-9550 7300) $PN 2
J 2
(-9560 7310);
DISPLAY 0.680851 (-9560 7310);
PAINT MONO (-9560 7310);
FORCEPROP 0 LASTPIN (-9550 7200) $PN 11
J 2
(-9560 7210);
DISPLAY 0.680851 (-9560 7210);
PAINT MONO (-9560 7210);
FORCEPROP 1 LAST VALUE TPS54424RNVT
J 0
(-9400 7700);
DISPLAY 1.212766 (-9400 7700);
PAINT GREEN (-9400 7700);
FORCEPROP 1 LAST CLS_PN G220-10657-01
J 0
(-9400 7600);
DISPLAY 1.212766 (-9400 7600);
PAINT GREEN (-9400 7600);
FORCEPROP 1 LAST PATH I42
J 0
(-9400 7450);
DISPLAY 1.212766 (-9400 7450);
PAINT GREEN (-9400 7450);
DISPLAY INVISIBLE (-9400 7450);
FORCEPROP 2 LAST CDS_LIB stdlogic
J 0
(-9450 7400);
DISPLAY INVISIBLE (-9450 7400);
FORCEPROP 1 LAST CDS_LMAN_SYM_OUTLINE 0,0,1000,-1750
J 0
(-9450 7400);
DISPLAY 0.468085 (-9450 7400);
PAINT GREEN (-9450 7400);
DISPLAY INVISIBLE (-9450 7400);
FORCEADD OFFPAGE_IN..1
(-14500 7000);
FORCEPROP 2 LAST $XR3 31J2< 
J 0
(-15284 7000);
DISPLAY 0.638298 (-15284 7000);
PAINT MONO (-15284 7000);
FORCEPROP 2 LAST $XR2 31D3< 
J 0
(-15104 7000);
DISPLAY 0.638298 (-15104 7000);
PAINT MONO (-15104 7000);
FORCEPROP 2 LAST $XR1 30K11> 
J 0
(-14924 7000);
DISPLAY 0.638298 (-14924 7000);
PAINT MONO (-14924 7000);
FORCEPROP 2 LAST $XR0 25F6<> 
J 0
(-14714 7000);
DISPLAY 0.638298 (-14714 7000);
PAINT MONO (-14714 7000);
FORCEPROP 2 LAST CDS_LIB cls
J 0
(-14500 7000);
DISPLAY INVISIBLE (-14500 7000);
FORCEPROP 1 LAST CDS_LMAN_SYM_OUTLINE -50,50,50,-50
J 0
(-14500 7000);
DISPLAY 0.468085 (-14500 7000);
PAINT GREEN (-14500 7000);
DISPLAY INVISIBLE (-14500 7000);
FORCEPROP 1 LAST BODY_TYPE COMMENT
J 0
(-14490 7135);
DISPLAY 0.808511 (-14490 7135);
PAINT GREEN (-14490 7135);
DISPLAY INVISIBLE (-14490 7135);
FORCEPROP 1 LAST OFFPAGE TRUE
J 0
(-14490 7055);
DISPLAY 0.808511 (-14490 7055);
PAINT GREEN (-14490 7055);
DISPLAY INVISIBLE (-14490 7055);
FORCEPROP 2 LAST PATH I43
J 0
(-14450 7100);
DISPLAY 1.021277 (-14450 7100);
DISPLAY INVISIBLE (-14450 7100);
FORCEADD RESISTOR..1
(-13400 7000);
FORCEPROP 1 LAST $LOCATION R142
J 2
(-13501 7055);
DISPLAY 1.212766 (-13501 7055);
PAINT GREEN (-13501 7055);
FORCEPROP 0 LAST CDS_LOCATION R142
J 0
(-13300 7150);
DISPLAY 1.021277 (-13300 7150);
DISPLAY INVISIBLE (-13300 7150);
FORCEPROP 0 LAST $SEC 1
J 0
(-13300 7150);
DISPLAY 0.680851 (-13300 7150);
PAINT MONO (-13300 7150);
DISPLAY INVISIBLE (-13300 7150);
FORCEPROP 0 LAST CDS_SEC 1
J 0
(-13300 7150);
DISPLAY 1.021277 (-13300 7150);
DISPLAY INVISIBLE (-13300 7150);
FORCEPROP 0 LASTPIN (-13500 7000) $PN 1
J 2
(-13510 7010);
DISPLAY 0.680851 (-13510 7010);
PAINT MONO (-13510 7010);
FORCEPROP 0 LASTPIN (-13250 7000) $PN 2
J 0
(-13240 7010);
DISPLAY 0.680851 (-13240 7010);
PAINT MONO (-13240 7010);
FORCEPROP 1 LAST VALUE 100OHM
J 0
(-13300 7050);
DISPLAY 1.212766 (-13300 7050);
PAINT GREEN (-13300 7050);
FORCEPROP 0 LAST PACKAGE 0402
J 0
(-13500 7150);
DISPLAY 1.021277 (-13500 7150);
FORCEPROP 1 LAST PATH I44
J 0
(-13597 7105);
DISPLAY 1.212766 (-13597 7105);
PAINT GREEN (-13597 7105);
DISPLAY INVISIBLE (-13597 7105);
FORCEPROP 1 LAST TOLERANCE 1%
J 0
(-13597 7255);
DISPLAY 1.212766 (-13597 7255);
PAINT GREEN (-13597 7255);
DISPLAY INVISIBLE (-13597 7255);
FORCEPROP 2 LAST CDS_LIB passive
J 0
(-13400 7000);
DISPLAY INVISIBLE (-13400 7000);
FORCEPROP 1 LAST CDS_LMAN_SYM_OUTLINE -50,50,100,-50
J 0
(-13400 7000);
DISPLAY 0.468085 (-13400 7000);
PAINT GREEN (-13400 7000);
DISPLAY INVISIBLE (-13400 7000);
FORCEPROP 1 LAST CLS_PN G155-11000-01
J 0
(-13536 7200);
DISPLAY 1.212766 (-13536 7200);
PAINT GREEN (-13536 7200);
DISPLAY INVISIBLE (-13536 7200);
FORCEADD RESISTOR..1
(-11550 4900);
FORCEPROP 1 LAST $LOCATION R294
J 2
(-11750 4900);
DISPLAY 1.212766 (-11750 4900);
PAINT GREEN (-11750 4900);
FORCEPROP 0 LAST CDS_LOCATION R294
J 0
(-11350 5000);
DISPLAY 1.021277 (-11350 5000);
DISPLAY INVISIBLE (-11350 5000);
FORCEPROP 0 LAST $SEC 1
J 0
(-11350 5000);
DISPLAY 0.680851 (-11350 5000);
PAINT MONO (-11350 5000);
DISPLAY INVISIBLE (-11350 5000);
FORCEPROP 0 LAST CDS_SEC 1
J 0
(-11350 5000);
DISPLAY 1.021277 (-11350 5000);
DISPLAY INVISIBLE (-11350 5000);
FORCEPROP 0 LASTPIN (-11650 4900) $PN 1
J 2
(-11660 4910);
DISPLAY 0.680851 (-11660 4910);
PAINT MONO (-11660 4910);
FORCEPROP 0 LASTPIN (-11400 4900) $PN 2
J 0
(-11390 4910);
DISPLAY 0.680851 (-11390 4910);
PAINT MONO (-11390 4910);
FORCEPROP 1 LAST VALUE 33OHM
J 0
(-11350 4900);
DISPLAY 1.234043 (-11350 4900);
PAINT GREEN (-11350 4900);
FORCEPROP 0 LAST PACKAGE 0402
J 0
(-11600 4950);
DISPLAY 1.021277 (-11600 4950);
FORCEPROP 0 LAST NO_ASSY TRUE
J 0
(-11800 4800);
DISPLAY 1.021277 (-11800 4800);
DISPLAY BOTH (-11800 4800);
FORCEPROP 1 LAST PATH I45
J 0
(-11747 5005);
DISPLAY 1.212766 (-11747 5005);
PAINT GREEN (-11747 5005);
DISPLAY INVISIBLE (-11747 5005);
FORCEPROP 1 LAST TOLERANCE 1%
J 0
(-11747 5155);
DISPLAY 1.212766 (-11747 5155);
PAINT GREEN (-11747 5155);
DISPLAY INVISIBLE (-11747 5155);
FORCEPROP 1 LAST CLS_PN G155-133R0-01
J 0
(-11686 5100);
DISPLAY 1.212766 (-11686 5100);
PAINT GREEN (-11686 5100);
DISPLAY INVISIBLE (-11686 5100);
FORCEPROP 2 LAST SIGNAL_MODEL DEFAULT_RESISTOR_33OHM_2_1
J 0
(-11700 5100);
DISPLAY 1.021277 (-11700 5100);
DISPLAY INVISIBLE (-11700 5100);
FORCEPROP 1 LAST CDS_LMAN_SYM_OUTLINE -50,50,100,-50
J 0
(-11550 4900);
DISPLAY 0.468085 (-11550 4900);
PAINT GREEN (-11550 4900);
DISPLAY INVISIBLE (-11550 4900);
FORCEPROP 2 LAST CDS_LIB passive
J 0
(-11550 4900);
DISPLAY INVISIBLE (-11550 4900);
FORCEADD OFFPAGE_OUT..1
(-9850 4900);
FORCEPROP 2 LAST $XR0 24F15> 
J 0
(-9795 4900);
DISPLAY 0.638298 (-9795 4900);
PAINT MONO (-9795 4900);
FORCEPROP 2 LAST $XR1 25C9<> 
J 0
(-9585 4900);
DISPLAY 0.638298 (-9585 4900);
PAINT MONO (-9585 4900);
FORCEPROP 2 LAST $XR2 31D7> 
J 0
(-9405 4900);
DISPLAY 0.638298 (-9405 4900);
PAINT MONO (-9405 4900);
FORCEPROP 2 LAST $XR3 31K11> 
J 0
(-9195 4900);
DISPLAY 0.638298 (-9195 4900);
PAINT MONO (-9195 4900);
FORCEPROP 2 LAST PATH I46
J 0
(-9800 5000);
DISPLAY 1.021277 (-9800 5000);
DISPLAY INVISIBLE (-9800 5000);
FORCEPROP 1 LAST OFFPAGE TRUE
J 0
(-9840 4955);
DISPLAY 0.808511 (-9840 4955);
PAINT GREEN (-9840 4955);
DISPLAY INVISIBLE (-9840 4955);
FORCEPROP 2 LAST CDS_LIB cls
J 0
(-9850 4900);
DISPLAY INVISIBLE (-9850 4900);
FORCEPROP 1 LAST CDS_LMAN_SYM_OUTLINE -50,50,50,-50
J 0
(-9850 4900);
DISPLAY 0.468085 (-9850 4900);
PAINT GREEN (-9850 4900);
DISPLAY INVISIBLE (-9850 4900);
FORCEPROP 1 LAST BODY_TYPE COMMENT
J 0
(-9840 5035);
DISPLAY 0.808511 (-9840 5035);
PAINT GREEN (-9840 5035);
DISPLAY INVISIBLE (-9840 5035);
FORCEPROP 2 LAST $XR4 10F12< 
J 0
(-9195 4900);
DISPLAY 0.638298 (-9195 4900);
PAINT MONO (-9195 4900);
FORCEADD VCC..1
(-13750 8700);
FORCEPROP 3 LASTPIN (-13700 8650) SIG_NAME XP12R0V\g
J 0
(-13690 8660);
DISPLAY 0.659574 (-13690 8660);
PAINT MONO (-13690 8660);
DISPLAY INVISIBLE (-13690 8660);
FORCEPROP 1 LAST HDL_POWER XP12R0V
J 1
(-13695 8755);
DISPLAY 1.021277 (-13695 8755);
PAINT GREEN (-13695 8755);
FORCEPROP 0 LAST VOLTAGE 12V
J 0
(-13950 8800);
DISPLAY 1.021277 (-13950 8800);
DISPLAY BOTH (-13950 8800);
FORCEPROP 1 LAST PATH I5
J 0
(-13715 8790);
DISPLAY 0.808511 (-13715 8790);
PAINT GREEN (-13715 8790);
DISPLAY INVISIBLE (-13715 8790);
FORCEPROP 1 LAST BODY_TYPE PLUMBING
J 0
(-13795 8657);
DISPLAY 0.340426 (-13795 8657);
PAINT GREEN (-13795 8657);
DISPLAY INVISIBLE (-13795 8657);
FORCEPROP 2 LAST CDS_LIB cls
J 0
(-13750 8700);
DISPLAY INVISIBLE (-13750 8700);
FORCEPROP 1 LAST CDS_LMAN_SYM_OUTLINE -250,250,250,-250
J 0
(-13750 8700);
DISPLAY 0.468085 (-13750 8700);
PAINT GREEN (-13750 8700);
DISPLAY INVISIBLE (-13750 8700);
FORCEADD GND_SG..1
(-13200 5150);
FORCEPROP 3 LASTPIN (-13150 5200) SIG_NAME SG\g
J 0
(-13140 5210);
DISPLAY 0.659574 (-13140 5210);
PAINT MONO (-13140 5210);
DISPLAY INVISIBLE (-13140 5210);
FORCEPROP 1 LAST HDL_POWER SG
J 1
(-13145 5055);
DISPLAY 0.808511 (-13145 5055);
PAINT GREEN (-13145 5055);
FORCEPROP 1 LAST PATH I6
J 0
(-13165 5150);
DISPLAY 0.808511 (-13165 5150);
PAINT GREEN (-13165 5150);
DISPLAY INVISIBLE (-13165 5150);
FORCEPROP 1 LAST BODY_TYPE PLUMBING
J 0
(-13185 5135);
DISPLAY 0.808511 (-13185 5135);
PAINT GREEN (-13185 5135);
DISPLAY INVISIBLE (-13185 5135);
FORCEPROP 2 LAST CDS_LIB cls
J 0
(-13200 5150);
DISPLAY INVISIBLE (-13200 5150);
FORCEPROP 1 LAST CDS_LMAN_SYM_OUTLINE 0,0,100,-50
J 0
(-13200 5150);
DISPLAY 0.468085 (-13200 5150);
PAINT GREEN (-13200 5150);
DISPLAY INVISIBLE (-13200 5150);
FORCEADD CAPACITOR..1
R 1
(-13150 5450);
FORCEPROP 1 LAST $LOCATION C75
R 1
J 2
(-13250 5550);
DISPLAY 1.212766 (-13250 5550);
PAINT GREEN (-13250 5550);
FORCEPROP 0 LAST CDS_LOCATION C75
R 1
J 0
(-13050 5650);
DISPLAY 1.021277 (-13050 5650);
DISPLAY INVISIBLE (-13050 5650);
FORCEPROP 0 LAST $SEC 1
R 1
J 0
(-13050 5650);
DISPLAY 0.680851 (-13050 5650);
PAINT MONO (-13050 5650);
DISPLAY INVISIBLE (-13050 5650);
FORCEPROP 0 LAST CDS_SEC 1
R 1
J 0
(-13050 5650);
DISPLAY 1.021277 (-13050 5650);
DISPLAY INVISIBLE (-13050 5650);
FORCEPROP 0 LASTPIN (-13150 5350) $PN 1
R 1
J 2
(-13160 5340);
DISPLAY 0.680851 (-13160 5340);
PAINT MONO (-13160 5340);
FORCEPROP 0 LASTPIN (-13150 5600) $PN 2
R 1
J 0
(-13160 5610);
DISPLAY 0.680851 (-13160 5610);
PAINT MONO (-13160 5610);
FORCEPROP 0 LAST PACKAGE 0201
J 0
(-13050 5350);
DISPLAY 1.021277 (-13050 5350);
FORCEPROP 0 LAST VOLTAGE 25V
J 0
(-13050 5550);
DISPLAY 1.021277 (-13050 5550);
FORCEPROP 1 LAST VALUE 0.01UF
J 0
(-13050 5450);
DISPLAY 1.212766 (-13050 5450);
PAINT GREEN (-13050 5450);
FORCEPROP 1 LAST PATH I7
R 1
J 2
(-13250 5400);
DISPLAY 1.212766 (-13250 5400);
PAINT GREEN (-13250 5400);
DISPLAY INVISIBLE (-13250 5400);
FORCEPROP 1 LAST CLS_PN G104-0B103-EK
R 1
J 2
(-13250 5400);
DISPLAY 1.212766 (-13250 5400);
PAINT GREEN (-13250 5400);
DISPLAY INVISIBLE (-13250 5400);
FORCEPROP 1 LAST CDS_LMAN_SYM_OUTLINE 0,50,50,-50
R 1
J 0
(-13150 5450);
DISPLAY 0.468085 (-13150 5450);
PAINT GREEN (-13150 5450);
DISPLAY INVISIBLE (-13150 5450);
FORCEPROP 2 LAST CDS_LIB passive
J 0
(-13150 5450);
DISPLAY INVISIBLE (-13150 5450);
FORCEPROP 1 LAST TOLERANCE 10%
R 1
J 2
(-13250 5350);
DISPLAY 1.212766 (-13250 5350);
PAINT GREEN (-13250 5350);
DISPLAY INVISIBLE (-13250 5350);
FORCEADD GND_SG..1
(-12650 6050);
FORCEPROP 3 LASTPIN (-12600 6100) SIG_NAME SG\g
J 0
(-12590 6110);
DISPLAY 0.659574 (-12590 6110);
PAINT MONO (-12590 6110);
DISPLAY INVISIBLE (-12590 6110);
FORCEPROP 1 LAST HDL_POWER SG
J 1
(-12595 5955);
DISPLAY 0.808511 (-12595 5955);
PAINT GREEN (-12595 5955);
FORCEPROP 1 LAST PATH I8
J 0
(-12615 6050);
DISPLAY 0.808511 (-12615 6050);
PAINT GREEN (-12615 6050);
DISPLAY INVISIBLE (-12615 6050);
FORCEPROP 1 LAST BODY_TYPE PLUMBING
J 0
(-12635 6035);
DISPLAY 0.808511 (-12635 6035);
PAINT GREEN (-12635 6035);
DISPLAY INVISIBLE (-12635 6035);
FORCEPROP 1 LAST CDS_LMAN_SYM_OUTLINE 0,0,100,-50
J 0
(-12650 6050);
DISPLAY 0.468085 (-12650 6050);
PAINT GREEN (-12650 6050);
DISPLAY INVISIBLE (-12650 6050);
FORCEPROP 2 LAST CDS_LIB cls
J 0
(-12650 6050);
DISPLAY INVISIBLE (-12650 6050);
FORCEADD RESISTOR..2
(-12950 6600);
FORCEPROP 1 LAST $LOCATION R48
J 0
(-12900 6450);
DISPLAY 1.212766 (-12900 6450);
PAINT GREEN (-12900 6450);
FORCEPROP 0 LAST CDS_LOCATION R48
J 0
(-13400 6700);
DISPLAY 1.021277 (-13400 6700);
DISPLAY INVISIBLE (-13400 6700);
FORCEPROP 0 LAST $SEC 1
J 0
(-13400 6700);
DISPLAY 0.680851 (-13400 6700);
PAINT MONO (-13400 6700);
DISPLAY INVISIBLE (-13400 6700);
FORCEPROP 0 LAST CDS_SEC 1
J 0
(-13400 6700);
DISPLAY 1.021277 (-13400 6700);
DISPLAY INVISIBLE (-13400 6700);
FORCEPROP 0 LASTPIN (-12950 6700) $PN 1
R 1
J 0
(-12960 6710);
DISPLAY 0.680851 (-12960 6710);
PAINT MONO (-12960 6710);
FORCEPROP 0 LASTPIN (-12950 6450) $PN 2
R 1
J 2
(-12960 6440);
DISPLAY 0.680851 (-12960 6440);
PAINT MONO (-12960 6440);
FORCEPROP 1 LAST VALUE 5.1KOHM
J 0
(-13400 6600);
DISPLAY 1.212766 (-13400 6600);
PAINT GREEN (-13400 6600);
FORCEPROP 0 LAST PACKAGE 0402
J 0
(-13250 6700);
DISPLAY 1.021277 (-13250 6700);
FORCEPROP 0 LAST NO_ASSY TRUE
J 0
(-13600 6500);
DISPLAY 1.021277 (-13600 6500);
DISPLAY BOTH (-13600 6500);
FORCEPROP 1 LAST PATH I9
J 0
(-13147 6705);
DISPLAY 1.212766 (-13147 6705);
PAINT GREEN (-13147 6705);
DISPLAY INVISIBLE (-13147 6705);
FORCEPROP 1 LAST TOLERANCE 1%
J 0
(-13147 6855);
DISPLAY 1.212766 (-13147 6855);
PAINT GREEN (-13147 6855);
DISPLAY INVISIBLE (-13147 6855);
FORCEPROP 1 LAST CDS_LMAN_SYM_OUTLINE -50,50,50,-100
J 0
(-12950 6600);
DISPLAY 0.468085 (-12950 6600);
PAINT GREEN (-12950 6600);
DISPLAY INVISIBLE (-12950 6600);
FORCEPROP 2 LAST CDS_LIB passive
J 0
(-12950 6600);
DISPLAY INVISIBLE (-12950 6600);
FORCEPROP 1 LAST CLS_PN A155-05101-DL
J 0
(-13086 6800);
DISPLAY 1.212766 (-13086 6800);
PAINT GREEN (-13086 6800);
DISPLAY INVISIBLE (-13086 6800);
FORCEADD SHEET_A1..1
(-250 350);
FORCEPROP 2 LAST CUSTOM_TXT_CDS <XR_PAGE_TITLE>
J 0
(-15820 11700);
DISPLAY 0.638298 (-15820 11700);
PAINT PINK (-15820 11700);
FORCEPROP 1 LAST CUSTOM_TXT_CDS <DOCNO>
J 0
(-2300 735);
DISPLAY 0.978723 (-2300 735);
FORCEPROP 1 LAST CUSTOM_TXT_CDS <CON_PAGE_NUM>
J 0
(-2405 400);
DISPLAY 0.978723 (-2405 400);
FORCEPROP 1 LAST CUSTOM_TXT_CDS <DATE>
J 0
(-950 525);
DISPLAY 0.978723 (-950 525);
FORCEPROP 1 LAST CUSTOM_TXT_CDS <TITLE>
J 1
(-2035 980);
DISPLAY 0.978723 (-2035 980);
FORCEPROP 1 LAST CUSTOM_TXT_CDS <DESIGNER>
J 0
(-950 950);
DISPLAY 0.978723 (-950 950);
FORCEPROP 1 LAST CUSTOM_TXT_CDS <CON_TOTAL_PAGES>
J 0
(-2095 400);
DISPLAY 0.808511 (-2095 400);
FORCEPROP 1 LAST CUSTOM_TXT_CDS <ASSY_PN>
J 0
(-2300 525);
DISPLAY 0.978723 (-2300 525);
FORCEPROP 1 LAST CUSTOM_TXT_CDS <DOCREV>
J 0
(-950 725);
DISPLAY 0.978723 (-950 725);
FORCEPROP 1 LAST TITLE XP5R0V
J 0
(-2750 1200);
DISPLAY 3.042553 (-2750 1200);
PAINT GREEN (-2750 1200);
FORCEPROP 2 LAST CDS_LIB cls
J 0
(-250 350);
DISPLAY INVISIBLE (-250 350);
FORCEPROP 1 LAST CDS_LMAN_SYM_OUTLINE -15850,11500,200,-200
J 0
(-250 350);
DISPLAY 0.468085 (-250 350);
PAINT GREEN (-250 350);
DISPLAY INVISIBLE (-250 350);
FORCEPROP 2 LAST PAGE_BORDER TRUE
J 0
(-15820 11700);
DISPLAY 0.638298 (-15820 11700);
PAINT PINK (-15820 11700);
DISPLAY INVISIBLE (-15820 11700);
FORCEPROP 1 LAST COMMENT_BODY TRUE
J 0
(-240 405);
DISPLAY 0.808511 (-240 405);
PAINT GREEN (-240 405);
DISPLAY INVISIBLE (-240 405);
FORCEPROP 2 LAST CDS_XR_PAGE_TITLE CR-32 : @TIMECARD_LIB.TIMECARD(SCH_1):PAGE32
J 0
(-15820 11700);
DISPLAY 0.638298 (-15820 11700);
PAINT PINK (-15820 11700);
DISPLAY INVISIBLE (-15820 11700);
WIRE 16 -1 (-14450 7000)(-13500 7000);
FORCEPROP 2 LAST SIG_NAME XP1R8V_FPGA_PG
J 0
(-14410 7010);
DISPLAY 1.021277 (-14410 7010);
WIRE 16 -1 (-3400 7450)(-3400 7350);
WIRE 16 -1 (-3800 7450)(-3400 7450);
WIRE 16 -1 (-13700 7850)(-13700 7650);
WIRE 16 -1 (-13950 6200)(-13950 6450);
WIRE 16 -1 (-13150 5350)(-13150 5200);
WIRE 16 -1 (-11400 4900)(-9900 4900);
FORCEPROP 2 LAST SIG_NAME FPGA_CFG_INIT_N
J 0
(-10660 4910);
DISPLAY 1.021277 (-10660 4910);
WIRE 16 -1 (-10700 5900)(-10700 5850);
WIRE 16 -1 (-13700 8650)(-13700 8250);
WIRE 16 -1 (-13700 8250)(-13300 8250);
WIRE 16 -1 (-13700 8100)(-13700 8250);
WIRE 16 -1 (-8350 7300)(-7200 7300);
FORCEPROP 2 LAST SIG_NAME XP5R0V_BT
J 1
(-7810 7310);
DISPLAY 1.021277 (-7810 7310);
WIRE 16 -1 (-6950 7300)(-6300 7300);
WIRE 16 -1 (-4050 7450)(-4750 7450);
WIRE 16 -1 (-11850 6600)(-9550 6600);
FORCEPROP 2 LAST SIG_NAME XP5R0V_SS
J 0
(-10560 6610);
DISPLAY 1.021277 (-10560 6610);
WIRE 16 -1 (-11850 6200)(-11850 6600);
WIRE 16 -1 (-9550 6400)(-11300 6400);
FORCEPROP 2 LAST SIG_NAME XP5R0V_RT
J 0
(-10560 6410);
DISPLAY 1.021277 (-10560 6410);
WIRE 16 -1 (-11300 6000)(-11300 6400);
WIRE 16 -1 (-12150 6800)(-9550 6800);
WIRE 16 -1 (-12150 5750)(-12150 6800);
WIRE 16 -1 (-12150 5750)(-12150 4900);
WIRE 16 -1 (-12150 5750)(-13150 5750);
WIRE 16 -1 (-13150 5600)(-13150 5750);
WIRE 16 -1 (-13150 5750)(-13950 5750);
FORCEPROP 2 LAST SIG_NAME XP5R0V_PG
J 0
(-13760 5760);
DISPLAY 1.021277 (-13760 5760);
WIRE 16 -1 (-12150 4900)(-11650 4900);
WIRE 16 -1 (-13950 5950)(-13950 5750);
WIRE 16 -1 (-12600 6100)(-12600 6250);
WIRE 16 -1 (-12600 6250)(-12600 6450);
WIRE 16 -1 (-12950 6250)(-12600 6250);
WIRE 16 -1 (-12950 6450)(-12950 6250);
WIRE 16 -1 (-12600 6700)(-12600 7000);
WIRE 16 -1 (-9550 7000)(-12600 7000);
FORCEPROP 2 LAST SIG_NAME R_XP5R0V_EN
J 0
(-12510 7010);
DISPLAY 1.021277 (-12510 7010);
WIRE 16 -1 (-12600 7000)(-12700 7000);
WIRE 16 -1 (-12700 7750)(-12700 7000);
WIRE 16 -1 (-12950 7000)(-12700 7000);
WIRE 16 -1 (-12950 6700)(-12950 7000);
WIRE 16 -1 (-13250 7000)(-12950 7000);
WIRE 16 -1 (-9700 5800)(-9550 5800);
WIRE 16 -1 (-9700 5800)(-9700 5450);
WIRE 16 -1 (-9700 5450)(-10050 5450);
WIRE 16 -1 (-10050 5700)(-10050 5450);
WIRE 16 -1 (-10050 5450)(-10700 5450);
WIRE 16 -1 (-10700 5600)(-10700 5450);
WIRE 16 -1 (-10700 5450)(-11300 5450);
FORCEPROP 2 LAST SIG_NAME XP5R0V_AGND
J 0
(-11310 5360);
DISPLAY 1.021277 (-11310 5360);
WIRE 16 -1 (-11300 5750)(-11300 5450);
WIRE 16 -1 (-11850 5450)(-11300 5450);
WIRE 16 -1 (-11850 5950)(-11850 5450);
WIRE 16 -1 (-10800 7450)(-10800 7600);
WIRE 16 -1 (-10800 7800)(-10800 7600);
WIRE 16 -1 (-10800 7600)(-11350 7600);
WIRE 16 -1 (-11350 7800)(-11350 7600);
WIRE 16 -1 (-11350 7600)(-11800 7600);
WIRE 16 -1 (-11800 7600)(-11800 7800);
WIRE 16 -1 (-12250 7600)(-11800 7600);
WIRE 16 -1 (-12250 7800)(-12250 7600);
WIRE 16 -1 (-10700 6150)(-10700 6200);
WIRE 16 -1 (-10700 6200)(-10050 6200);
FORCEPROP 2 LAST SIG_NAME XP5R0V_COMP
J 0
(-10610 6210);
DISPLAY 1.021277 (-10610 6210);
WIRE 16 -1 (-10050 6200)(-9550 6200);
WIRE 16 -1 (-10050 5950)(-10050 6200);
WIRE 16 -1 (-12700 8000)(-12700 8250);
WIRE 16 -1 (-12700 8250)(-12250 8250);
FORCEPROP 2 LAST SIG_NAME VIN_XP5R0V
J 0
(-10210 7310);
DISPLAY 1.021277 (-10210 7310);
WIRE 16 -1 (-12900 8250)(-12700 8250);
WIRE 16 -1 (-12250 8050)(-12250 8250);
WIRE 16 -1 (-11800 8250)(-12250 8250);
WIRE 16 -1 (-11800 8050)(-11800 8250);
WIRE 16 -1 (-11350 8250)(-11800 8250);
WIRE 16 -1 (-11350 8050)(-11350 8250);
WIRE 16 -1 (-11350 8250)(-10800 8250);
WIRE 16 -1 (-10800 8050)(-10800 8250);
WIRE 16 -1 (-10300 8250)(-10800 8250);
WIRE 16 -1 (-10300 8250)(-10300 7300);
WIRE 16 -1 (-9550 7300)(-10300 7300);
WIRE 16 -1 (-10300 7300)(-10300 7200);
WIRE 16 -1 (-10300 7200)(-9550 7200);
WIRE 16 -1 (-8350 6300)(-8000 6300);
WIRE 16 -1 (-8000 6300)(-8000 6200);
WIRE 16 -1 (-8350 6200)(-8000 6200);
WIRE 16 -1 (-8000 6200)(-8000 6100);
WIRE 16 -1 (-8350 6100)(-8000 6100);
WIRE 16 -1 (-8000 6100)(-8000 6000);
WIRE 16 -1 (-8000 6000)(-8000 5900);
WIRE 16 -1 (-8350 6000)(-8000 6000);
WIRE 16 -1 (-8000 5900)(-8000 5800);
WIRE 16 -1 (-8350 5900)(-8000 5900);
WIRE 16 -1 (-8000 5800)(-8000 5050);
WIRE 16 -1 (-8350 5800)(-8000 5800);
WIRE 16 -1 (-7600 5050)(-8000 5050);
WIRE 16 -1 (-8000 5050)(-8000 4750);
WIRE 16 -1 (-5000 7450)(-5350 7450);
WIRE 16 -1 (-5350 7100)(-5350 7450);
WIRE 16 -1 (-5350 7100)(-5000 7100);
WIRE 16 -1 (-5700 7100)(-5350 7100);
WIRE 16 -1 (-5700 7300)(-5700 7100);
WIRE 16 -1 (-8200 7100)(-5700 7100);
FORCEPROP 2 LAST SIG_NAME XP5R0V_SW
J 1
(-7810 7110);
DISPLAY 1.021277 (-7810 7110);
WIRE 16 -1 (-8350 7100)(-8200 7100);
WIRE 16 -1 (-8200 7000)(-8200 7100);
WIRE 16 -1 (-6050 7300)(-5700 7300);
WIRE 16 -1 (-8350 7000)(-8200 7000);
WIRE 16 -1 (-4800 5300)(-4800 5050);
WIRE 16 -1 (-4800 5050)(-5400 5050);
WIRE 16 -1 (-5400 5300)(-5400 5050);
WIRE 16 -1 (-7150 5050)(-5400 5050);
FORCEPROP 2 LAST SIG_NAME XP5R0V_AGND
J 0
(-7010 5060);
DISPLAY 1.021277 (-7010 5060);
WIRE 16 -1 (-3350 6000)(-3350 5750);
WIRE 16 -1 (-3350 5750)(-4000 5750);
WIRE 16 -1 (-4000 5950)(-4000 5750);
WIRE 16 -1 (-4000 5750)(-4800 5750);
WIRE 16 -1 (-4800 5550)(-4800 5750);
WIRE 16 -1 (-4800 5750)(-5400 5750);
WIRE 16 -1 (-5400 6600)(-5400 5750);
WIRE 16 -1 (-5400 5550)(-5400 5750);
WIRE 16 -1 (-8350 6600)(-5400 6600);
FORCEPROP 2 LAST SIG_NAME XP5R0V_FB_R_TO_AGND
J 0
(-7260 6610);
DISPLAY 1.021277 (-7260 6610);
WIRE 8 -1 (-1400 3550)(-1400 3400);
WIRE 8 -1 (-1400 3550)(-2350 3550);
WIRE 8 -1 (-1400 3400)(-1400 3250);
WIRE 8 -1 (-2350 3400)(-1400 3400);
WIRE 8 -1 (-2350 3400)(-2350 3550);
WIRE 8 -1 (-3200 3400)(-2350 3400);
WIRE 8 -1 (-2350 3250)(-2350 3400);
WIRE 8 -1 (-1400 3100)(-1400 3250);
WIRE 8 -1 (-2350 3250)(-1400 3250);
WIRE 8 -1 (-2350 3550)(-3200 3550);
WIRE 8 -1 (-3200 3550)(-3200 3400);
WIRE 8 -1 (-2350 3100)(-2350 3250);
WIRE 8 -1 (-3200 3250)(-2350 3250);
WIRE 8 -1 (-1400 2950)(-1400 3100);
WIRE 8 -1 (-2350 3100)(-1400 3100);
WIRE 8 -1 (-3200 3400)(-3200 3250);
WIRE 8 -1 (-3200 3100)(-3200 3250);
WIRE 8 -1 (-3200 3100)(-2350 3100);
WIRE 8 -1 (-2350 2950)(-2350 3100);
WIRE 8 -1 (-1400 2800)(-1400 2950);
WIRE 8 -1 (-2350 2950)(-1400 2950);
WIRE 8 -1 (-2350 2800)(-2350 2950);
WIRE 8 -1 (-3200 2950)(-2350 2950);
WIRE 8 -1 (-1400 2650)(-1400 2800);
WIRE 8 -1 (-2350 2800)(-1400 2800);
WIRE 8 -1 (-3200 2950)(-3200 3100);
WIRE 8 -1 (-3200 2800)(-3200 2950);
WIRE 8 -1 (-3200 2800)(-2350 2800);
WIRE 8 -1 (-2350 2650)(-2350 2800);
WIRE 8 -1 (-1400 2500)(-1400 2650);
WIRE 8 -1 (-1400 2650)(-2350 2650);
WIRE 8 -1 (-2350 2500)(-2350 2650);
WIRE 8 -1 (-2350 2650)(-3200 2650);
WIRE 8 -1 (-1400 2350)(-1400 2500);
WIRE 8 -1 (-1400 2500)(-2350 2500);
WIRE 8 -1 (-3200 2650)(-3200 2800);
WIRE 8 -1 (-3200 2500)(-3200 2650);
WIRE 8 -1 (-2350 2500)(-3200 2500);
WIRE 8 -1 (-2350 2350)(-2350 2500);
WIRE 8 -1 (-1400 2200)(-1400 2350);
WIRE 8 -1 (-1400 2350)(-2350 2350);
WIRE 8 -1 (-2350 2200)(-2350 2350);
WIRE 8 -1 (-2350 2350)(-3200 2350);
WIRE 8 -1 (-1400 2200)(-2350 2200);
WIRE 8 -1 (-3200 2350)(-3200 2500);
WIRE 8 -1 (-3200 2200)(-3200 2350);
WIRE 8 -1 (-2350 2200)(-3200 2200);
WIRE 16 -1 (-3350 6400)(-4000 6400);
WIRE 16 -1 (-3350 6400)(-3350 6250);
WIRE 16 -1 (-3350 6550)(-3350 6400);
WIRE 16 -1 (-4000 6400)(-4000 6200);
WIRE 16 -1 (-1000 7300)(-1000 7100);
WIRE 16 -1 (-1000 7100)(-1150 7100);
WIRE 16 -1 (-1150 6850)(-1150 7100);
WIRE 16 -1 (-1150 7100)(-1650 7100);
WIRE 16 -1 (-1650 6850)(-1650 7100);
WIRE 16 -1 (-1650 7100)(-2150 7100);
WIRE 16 -1 (-2150 6850)(-2150 7100);
WIRE 16 -1 (-2150 7100)(-2700 7100);
WIRE 16 -1 (-2700 7100)(-3350 7100);
WIRE 16 -1 (-2700 6850)(-2700 7100);
WIRE 16 -1 (-3350 6800)(-3350 7100);
WIRE 16 -1 (-3350 7100)(-4650 7100);
WIRE 16 -1 (-1150 6400)(-1150 6250);
WIRE 16 -1 (-1150 6400)(-1150 6600);
WIRE 16 -1 (-1650 6400)(-1150 6400);
WIRE 16 -1 (-1650 6600)(-1650 6400);
WIRE 16 -1 (-1650 6400)(-2150 6400);
WIRE 16 -1 (-2150 6600)(-2150 6400);
WIRE 16 -1 (-2700 6400)(-2150 6400);
WIRE 16 -1 (-2700 6600)(-2700 6400);
DOT 1 (-13150 5750);
DOT 1 (-12150 5750);
DOT 1 (-12600 6250);
DOT 1 (-12950 7000);
DOT 1 (-12600 7000);
DOT 1 (-12700 7000);
DOT 1 (-11300 5450);
DOT 1 (-10700 5450);
DOT 1 (-10050 5450);
DOT 1 (-11800 7600);
CIRCLE (-11050 7950)(-10536 7950);
PAINT PINK (-11050 7950);
DOT 1 (-11350 7600);
DOT 1 (-10050 6200);
DOT 1 (-10800 7600);
DOT 1 (-10300 7300);
DOT 1 (-8000 5050);
DOT 1 (-8000 5800);
DOT 1 (-8000 5900);
DOT 1 (-8000 6000);
DOT 1 (-8000 6100);
DOT 1 (-8000 6200);
DOT 1 (-8200 7100);
DOT 1 (-13700 8250);
DOT 1 (-12700 8250);
DOT 1 (-12250 8250);
DOT 1 (-11800 8250);
DOT 1 (-11350 8250);
DOT 1 (-10800 8250);
DOT 1 (-5400 5050);
DOT 1 (-5400 5750);
DOT 1 (-4800 5750);
DOT 1 (-4000 5750);
DOT 1 (-5700 7100);
DOT 1 (-5350 7100);
DOT 1 (-3200 2500);
DOT 1 (-3200 2350);
DOT 1 (-3200 2800);
DOT 1 (-3200 2650);
DOT 1 (-3200 2950);
DOT 1 (-3200 3250);
DOT 1 (-3200 3100);
DOT 1 (-3200 3400);
DOT 1 (-2350 2200);
DOT 1 (-2350 2350);
DOT 1 (-2350 2500);
DOT 1 (-2350 2650);
DOT 1 (-2350 2800);
DOT 1 (-2350 2950);
DOT 1 (-2350 3100);
DOT 1 (-2350 3250);
DOT 1 (-2350 3400);
DOT 1 (-2350 3550);
DOT 1 (-1400 2500);
DOT 1 (-1400 2350);
DOT 1 (-1400 2800);
DOT 1 (-1400 2650);
DOT 1 (-1400 2950);
DOT 1 (-1400 3250);
DOT 1 (-1400 3100);
DOT 1 (-1400 3400);
DOT 1 (-3350 6400);
DOT 1 (-3350 7100);
DOT 1 (-2700 7100);
DOT 1 (-2150 6400);
DOT 1 (-2150 7100);
DOT 1 (-1650 6400);
DOT 1 (-1650 7100);
DOT 1 (-1150 6400);
DOT 1 (-1150 7100);
FORCENOTE
PLACE NEAR TWO VIN SEPARATELY
(-11450 7500) 0;
DISPLAY LEFT (-11450 7500);
DISPLAY 1.021277 (-11450 7500);
PAINT PINK (-11450 7500);
FORCENOTE
VFB=0.6V
(-3950 5650) 0;
DISPLAY LEFT (-3950 5650);
DISPLAY 1.021277 (-3950 5650);
FORCENOTE
XP5R0V
(-3150 3600) 0;
DISPLAY LEFT (-3150 3600);
DISPLAY 1.595745 (-3150 3600);
PAINT VIOLET (-3150 3600);
FORCENOTE
POWER RAIL
(-3150 3450) 0;
DISPLAY LEFT (-3150 3450);
DISPLAY 1.595745 (-3150 3450);
FORCENOTE
VOUT
(-2950 3150) 0;
DISPLAY LEFT (-2950 3150);
DISPLAY 1.595745 (-2950 3150);
FORCENOTE
VIN
(-2900 3300) 0;
DISPLAY LEFT (-2900 3300);
DISPLAY 1.595745 (-2900 3300);
FORCENOTE
FSW
(-2900 2850) 0;
DISPLAY LEFT (-2900 2850);
DISPLAY 1.595745 (-2900 2850);
FORCENOTE
SS
(-2850 3000) 0;
DISPLAY LEFT (-2850 3000);
DISPLAY 1.595745 (-2850 3000);
FORCENOTE
IMAX
(-2950 2700) 0;
DISPLAY LEFT (-2950 2700);
DISPLAY 1.595745 (-2950 2700);
FORCENOTE
OCP
(-2900 2550) 0;
DISPLAY LEFT (-2900 2550);
DISPLAY 1.595745 (-2900 2550);
FORCENOTE
OVP
(-2900 2400) 0;
DISPLAY LEFT (-2900 2400);
DISPLAY 1.595745 (-2900 2400);
FORCENOTE
 RIPPLE
(-3100 2250) 0;
DISPLAY LEFT (-3100 2250);
DISPLAY 1.595745 (-3100 2250);
FORCENOTE
500KHZ
(-2100 2850) 0;
DISPLAY LEFT (-2100 2850);
DISPLAY 1.595745 (-2100 2850);
FORCENOTE
108%*VOUT
(-2200 2400) 0;
DISPLAY LEFT (-2200 2400);
DISPLAY 1.595745 (-2200 2400);
FORCENOTE
 +/- 1%
(-2150 2250) 0;
DISPLAY LEFT (-2150 2250);
DISPLAY 1.595745 (-2150 2250);
FORCENOTE
XP5R0V
(-2100 3450) 0;
DISPLAY LEFT (-2100 3450);
DISPLAY 1.595745 (-2100 3450);
FORCENOTE
12V
(-2000 3300) 0;
DISPLAY LEFT (-2000 3300);
DISPLAY 1.595745 (-2000 3300);
FORCENOTE
2.5MS
(-2050 3000) 0;
DISPLAY LEFT (-2050 3000);
DISPLAY 1.595745 (-2050 3000);
FORCENOTE
10A
(-2000 2550) 0;
DISPLAY LEFT (-2000 2550);
DISPLAY 1.595745 (-2000 2550);
FORCENOTE
2.6A
(-2000 2700) 0;
DISPLAY LEFT (-2000 2700);
DISPLAY 1.595745 (-2000 2700);
FORCENOTE
2.6A
(-1350 7150) 0;
DISPLAY LEFT (-1350 7150);
DISPLAY 1.595745 (-1350 7150);
FORCENOTE
XP5R0V
(-2100 3150) 0;
DISPLAY LEFT (-2100 3150);
DISPLAY 1.595745 (-2100 3150);
FORCENOTE
XP5R0V
(-8950 10150) 0;
DISPLAY LEFT (-8950 10150);
DISPLAY 6.148936 (-8950 10150);
PAINT VIOLET (-8950 10150);
QUIT
